FILE_TYPE = MACRO_DRAWING;
SET COLOR_WIRE YELLOW;
SET COLOR_PROP ORANGE;
SET COLOR_DOT WHITE;
SET COLOR_ARC YELLOW;
SET COLOR_BODY GREEN;
SET COLOR_NOTE PURPLE;
SET PROP_DISPLAY VALUE;
SET PAGE_NUMBER P214;
FORCEADD OFFPAGE..2
(9950 3325);
FORCEPROP 2 LAST $XR0 227 
J 0
(10139 3325);
DISPLAY 0.638298 (10139 3325);
PAINT MONO (10139 3325);
FORCEPROP 2 LAST PATH I100
J 0
(10150 3375);
DISPLAY 1.021277 (10150 3375);
DISPLAY INVISIBLE (10150 3375);
FORCEPROP 1 LAST COMMENT_BODY TRUE
J 0
(9905 3230);
DISPLAY 0.872340 (9905 3230);
PAINT PEACH (9905 3230);
DISPLAY INVISIBLE (9905 3230);
FORCEPROP 1 LAST OFFPAGE TRUE
J 0
(10275 3200);
DISPLAY 0.872340 (10275 3200);
PAINT GREEN (10275 3200);
DISPLAY INVISIBLE (10275 3200);
FORCEPROP 2 LAST CDS_LIB standard
J 0
(9950 3325);
PAINT MONO (9950 3325);
DISPLAY INVISIBLE (9950 3325);
FORCEADD Q_RES..1
(8675 3325);
FORCEPROP 1 LAST PART_NUMBER CS00002JB13
J 0
(8625 3375);
DISPLAY 0.404255 (8625 3375);
DISPLAY INVISIBLE (8625 3375);
FORCEPROP 1 LAST MATERIAL CHIP
J 0
(8925 3325);
DISPLAY 0.510638 (8925 3325);
FORCEPROP 1 LAST TOLERANCE 5%
J 0
(8850 3325);
DISPLAY 0.510638 (8850 3325);
FORCEPROP 1 LAST VALUE 0
J 2
(8825 3325);
DISPLAY 0.510638 (8825 3325);
FORCEPROP 1 LAST $LOCATION R2983
J 0
(8475 3325);
DISPLAY 0.510638 (8475 3325);
FORCEPROP 1 LASTPIN (8575 3325) $PN 1
J 0
(8587 3337);
DISPLAY 0.787234 (8587 3337);
PAINT MONO (8587 3337);
FORCEPROP 1 LASTPIN (8775 3325) $PN 2
J 0
(8737 3337);
DISPLAY 0.787234 (8737 3337);
PAINT MONO (8737 3337);
FORCEPROP 1 LAST PATH I101
J 0
(8625 3475);
DISPLAY 0.978723 (8625 3475);
PAINT WHITE (8625 3475);
DISPLAY INVISIBLE (8625 3475);
FORCEPROP 1 LAST WATTAGE 1/16W
J 2
(8850 3400);
DISPLAY 0.404255 (8850 3400);
DISPLAY INVISIBLE (8850 3400);
FORCEPROP 1 LAST PACK_TYPE 0402LF
J 0
(8925 3325);
DISPLAY 0.510638 (8925 3325);
DISPLAY INVISIBLE (8925 3325);
FORCEPROP 2 LAST CDS_LIB pure_quanta
J 0
(8675 3325);
DISPLAY INVISIBLE (8675 3325);
FORCEPROP 0 LAST CDS_LOCATION R2983
J 0
(8925 3350);
DISPLAY 1.021277 (8925 3350);
DISPLAY INVISIBLE (8925 3350);
FORCEPROP 0 LAST $SEC 1
J 0
(8925 3350);
DISPLAY 0.680851 (8925 3350);
PAINT MONO (8925 3350);
DISPLAY INVISIBLE (8925 3350);
FORCEPROP 0 LAST CDS_SEC 1
J 0
(8925 3350);
DISPLAY 1.021277 (8925 3350);
DISPLAY INVISIBLE (8925 3350);
FORCEADD OFFPAGE..1
(7450 3125);
FORCEPROP 2 LAST $XR1 144 
J 0
(7078 3125);
DISPLAY 0.638298 (7078 3125);
PAINT MONO (7078 3125);
FORCEPROP 2 LAST $XR0 142 
J 0
(7198 3125);
DISPLAY 0.638298 (7198 3125);
PAINT MONO (7198 3125);
FORCEPROP 1 LAST OFFPAGE TRUE
J 0
(7775 3000);
DISPLAY 0.872340 (7775 3000);
DISPLAY INVISIBLE (7775 3000);
FORCEPROP 1 LAST COMMENT_BODY TRUE
J 0
(7575 3025);
DISPLAY 1.170213 (7575 3025);
PAINT GREEN (7575 3025);
DISPLAY INVISIBLE (7575 3025);
FORCEPROP 2 LAST CDS_LIB standard
J 0
(7450 3125);
DISPLAY INVISIBLE (7450 3125);
FORCEPROP 2 LAST PATH I113
J 0
(7175 3175);
DISPLAY 1.021277 (7175 3175);
DISPLAY INVISIBLE (7175 3175);
FORCEADD OFFPAGE..2
(9950 3125);
FORCEPROP 2 LAST $XR0 227 
J 0
(10139 3125);
DISPLAY 0.638298 (10139 3125);
PAINT MONO (10139 3125);
FORCEPROP 1 LAST COMMENT_BODY TRUE
J 0
(9905 3030);
DISPLAY 0.872340 (9905 3030);
PAINT PEACH (9905 3030);
DISPLAY INVISIBLE (9905 3030);
FORCEPROP 1 LAST OFFPAGE TRUE
J 0
(10275 3000);
DISPLAY 0.872340 (10275 3000);
PAINT GREEN (10275 3000);
DISPLAY INVISIBLE (10275 3000);
FORCEPROP 2 LAST CDS_LIB standard
J 0
(9950 3125);
PAINT MONO (9950 3125);
DISPLAY INVISIBLE (9950 3125);
FORCEPROP 2 LAST PATH I114
J 0
(10275 3175);
DISPLAY 1.021277 (10275 3175);
DISPLAY INVISIBLE (10275 3175);
FORCEADD OFFPAGE..2
(9950 2925);
FORCEPROP 2 LAST $XR0 227 
J 0
(10139 2925);
DISPLAY 0.638298 (10139 2925);
PAINT MONO (10139 2925);
FORCEPROP 2 LAST CDS_LIB standard
J 0
(9950 2925);
PAINT MONO (9950 2925);
DISPLAY INVISIBLE (9950 2925);
FORCEPROP 1 LAST OFFPAGE TRUE
J 0
(10275 2800);
DISPLAY 0.872340 (10275 2800);
PAINT GREEN (10275 2800);
DISPLAY INVISIBLE (10275 2800);
FORCEPROP 1 LAST COMMENT_BODY TRUE
J 0
(9905 2830);
DISPLAY 0.872340 (9905 2830);
PAINT PEACH (9905 2830);
DISPLAY INVISIBLE (9905 2830);
FORCEPROP 2 LAST PATH I115
J 0
(10275 2975);
DISPLAY 1.021277 (10275 2975);
DISPLAY INVISIBLE (10275 2975);
FORCEADD OFFPAGE..2
(9950 2525);
FORCEPROP 2 LAST $XR0 227 
J 0
(10139 2525);
DISPLAY 0.638298 (10139 2525);
PAINT MONO (10139 2525);
FORCEPROP 1 LAST COMMENT_BODY TRUE
J 0
(9905 2430);
DISPLAY 0.872340 (9905 2430);
PAINT PEACH (9905 2430);
DISPLAY INVISIBLE (9905 2430);
FORCEPROP 1 LAST OFFPAGE TRUE
J 0
(10275 2400);
DISPLAY 0.872340 (10275 2400);
PAINT GREEN (10275 2400);
DISPLAY INVISIBLE (10275 2400);
FORCEPROP 2 LAST CDS_LIB standard
J 0
(9950 2525);
PAINT MONO (9950 2525);
DISPLAY INVISIBLE (9950 2525);
FORCEPROP 2 LAST PATH I116
J 0
(10150 2575);
DISPLAY 1.021277 (10150 2575);
DISPLAY INVISIBLE (10150 2575);
FORCEADD OFFPAGE..2
(9950 2725);
FORCEPROP 2 LAST $XR0 227 
J 0
(10139 2725);
DISPLAY 0.638298 (10139 2725);
PAINT MONO (10139 2725);
FORCEPROP 2 LAST PATH I117
J 0
(10150 2775);
DISPLAY 1.021277 (10150 2775);
DISPLAY INVISIBLE (10150 2775);
FORCEPROP 1 LAST COMMENT_BODY TRUE
J 0
(9905 2630);
DISPLAY 0.872340 (9905 2630);
PAINT PEACH (9905 2630);
DISPLAY INVISIBLE (9905 2630);
FORCEPROP 1 LAST OFFPAGE TRUE
J 0
(10275 2600);
DISPLAY 0.872340 (10275 2600);
PAINT GREEN (10275 2600);
DISPLAY INVISIBLE (10275 2600);
FORCEPROP 2 LAST CDS_LIB standard
J 0
(9950 2725);
PAINT MONO (9950 2725);
DISPLAY INVISIBLE (9950 2725);
FORCEADD Q_RES..1
(8675 3125);
FORCEPROP 1 LAST PART_NUMBER CS00002JB13
J 0
(8625 3175);
DISPLAY 0.404255 (8625 3175);
DISPLAY INVISIBLE (8625 3175);
FORCEPROP 1 LAST MATERIAL CHIP
J 0
(8925 3125);
DISPLAY 0.510638 (8925 3125);
FORCEPROP 1 LAST TOLERANCE 5%
J 0
(8850 3125);
DISPLAY 0.510638 (8850 3125);
FORCEPROP 1 LAST VALUE 0
J 2
(8825 3125);
DISPLAY 0.510638 (8825 3125);
FORCEPROP 1 LAST $LOCATION R3499
J 0
(8475 3125);
DISPLAY 0.510638 (8475 3125);
FORCEPROP 1 LASTPIN (8575 3125) $PN 1
J 0
(8587 3137);
DISPLAY 0.787234 (8587 3137);
PAINT MONO (8587 3137);
FORCEPROP 1 LASTPIN (8775 3125) $PN 2
J 0
(8737 3137);
DISPLAY 0.787234 (8737 3137);
PAINT MONO (8737 3137);
FORCEPROP 2 LAST CDS_LIB pure_quanta
J 0
(8675 3125);
DISPLAY INVISIBLE (8675 3125);
FORCEPROP 1 LAST PATH I118
J 0
(8625 3275);
DISPLAY 0.978723 (8625 3275);
PAINT WHITE (8625 3275);
DISPLAY INVISIBLE (8625 3275);
FORCEPROP 1 LAST PACK_TYPE 0402LF
J 0
(8925 3125);
DISPLAY 0.510638 (8925 3125);
DISPLAY INVISIBLE (8925 3125);
FORCEPROP 1 LAST WATTAGE 1/16W
J 2
(8850 3200);
DISPLAY 0.404255 (8850 3200);
DISPLAY INVISIBLE (8850 3200);
FORCEPROP 0 LAST CDS_LOCATION R3499
J 0
(8925 3150);
DISPLAY 1.021277 (8925 3150);
DISPLAY INVISIBLE (8925 3150);
FORCEPROP 0 LAST $SEC 1
J 0
(8925 3150);
DISPLAY 0.680851 (8925 3150);
PAINT MONO (8925 3150);
DISPLAY INVISIBLE (8925 3150);
FORCEPROP 0 LAST CDS_SEC 1
J 0
(8925 3150);
DISPLAY 1.021277 (8925 3150);
DISPLAY INVISIBLE (8925 3150);
FORCEADD OFFPAGE..1
(7450 2925);
FORCEPROP 2 LAST $XR1 144 
J 0
(7078 2925);
DISPLAY 0.638298 (7078 2925);
PAINT MONO (7078 2925);
FORCEPROP 2 LAST $XR0 142 
J 0
(7198 2925);
DISPLAY 0.638298 (7198 2925);
PAINT MONO (7198 2925);
FORCEPROP 2 LAST CDS_LIB standard
J 0
(7450 2925);
DISPLAY INVISIBLE (7450 2925);
FORCEPROP 1 LAST COMMENT_BODY TRUE
J 0
(7575 2825);
DISPLAY 1.170213 (7575 2825);
PAINT GREEN (7575 2825);
DISPLAY INVISIBLE (7575 2825);
FORCEPROP 1 LAST OFFPAGE TRUE
J 0
(7775 2800);
DISPLAY 0.872340 (7775 2800);
DISPLAY INVISIBLE (7775 2800);
FORCEPROP 2 LAST PATH I122
J 0
(7175 2975);
DISPLAY 1.021277 (7175 2975);
DISPLAY INVISIBLE (7175 2975);
FORCEADD OFFPAGE..1
(7450 2725);
FORCEPROP 2 LAST $XR1 144 
J 0
(7078 2725);
DISPLAY 0.638298 (7078 2725);
PAINT MONO (7078 2725);
FORCEPROP 2 LAST $XR0 142 
J 0
(7198 2725);
DISPLAY 0.638298 (7198 2725);
PAINT MONO (7198 2725);
FORCEPROP 2 LAST CDS_LIB standard
J 0
(7450 2725);
DISPLAY INVISIBLE (7450 2725);
FORCEPROP 1 LAST COMMENT_BODY TRUE
J 0
(7575 2625);
DISPLAY 1.170213 (7575 2625);
PAINT GREEN (7575 2625);
DISPLAY INVISIBLE (7575 2625);
FORCEPROP 1 LAST OFFPAGE TRUE
J 0
(7775 2600);
DISPLAY 0.872340 (7775 2600);
DISPLAY INVISIBLE (7775 2600);
FORCEPROP 2 LAST PATH I123
J 0
(7175 2775);
DISPLAY 1.021277 (7175 2775);
DISPLAY INVISIBLE (7175 2775);
FORCEADD OFFPAGE..1
(7450 2525);
FORCEPROP 2 LAST $XR1 144 
J 0
(7078 2525);
DISPLAY 0.638298 (7078 2525);
PAINT MONO (7078 2525);
FORCEPROP 2 LAST $XR0 142 
J 0
(7198 2525);
DISPLAY 0.638298 (7198 2525);
PAINT MONO (7198 2525);
FORCEPROP 1 LAST OFFPAGE TRUE
J 0
(7775 2400);
DISPLAY 0.872340 (7775 2400);
DISPLAY INVISIBLE (7775 2400);
FORCEPROP 1 LAST COMMENT_BODY TRUE
J 0
(7575 2425);
DISPLAY 1.170213 (7575 2425);
PAINT GREEN (7575 2425);
DISPLAY INVISIBLE (7575 2425);
FORCEPROP 2 LAST CDS_LIB standard
J 0
(7450 2525);
DISPLAY INVISIBLE (7450 2525);
FORCEPROP 2 LAST PATH I124
J 0
(7175 2575);
DISPLAY 1.021277 (7175 2575);
DISPLAY INVISIBLE (7175 2575);
FORCEADD Q_RES..1
(8675 2925);
FORCEPROP 1 LAST PART_NUMBER CS00002JB13
J 0
(8625 2975);
DISPLAY 0.404255 (8625 2975);
DISPLAY INVISIBLE (8625 2975);
FORCEPROP 1 LAST TOLERANCE 5%
J 0
(8850 2925);
DISPLAY 0.510638 (8850 2925);
FORCEPROP 1 LAST VALUE 0
J 2
(8825 2925);
DISPLAY 0.510638 (8825 2925);
FORCEPROP 1 LAST MATERIAL CHIP
J 0
(8925 2925);
DISPLAY 0.510638 (8925 2925);
FORCEPROP 1 LAST $LOCATION R3516
J 0
(8450 2925);
DISPLAY 0.638298 (8450 2925);
FORCEPROP 1 LASTPIN (8575 2925) $PN 1
J 0
(8587 2937);
DISPLAY 0.787234 (8587 2937);
PAINT MONO (8587 2937);
FORCEPROP 1 LASTPIN (8775 2925) $PN 2
J 0
(8737 2937);
DISPLAY 0.787234 (8737 2937);
PAINT MONO (8737 2937);
FORCEPROP 1 LAST WATTAGE 1/16W
J 2
(8850 3000);
DISPLAY 0.404255 (8850 3000);
DISPLAY INVISIBLE (8850 3000);
FORCEPROP 1 LAST PACK_TYPE 0402LF
J 0
(8925 2925);
DISPLAY 0.510638 (8925 2925);
DISPLAY INVISIBLE (8925 2925);
FORCEPROP 1 LAST PATH I127
J 0
(8625 3075);
DISPLAY 0.978723 (8625 3075);
PAINT WHITE (8625 3075);
DISPLAY INVISIBLE (8625 3075);
FORCEPROP 2 LAST CDS_LIB pure_quanta
J 0
(8675 2925);
DISPLAY INVISIBLE (8675 2925);
FORCEPROP 0 LAST CDS_LOCATION R3516
J 0
(8625 3025);
DISPLAY 1.021277 (8625 3025);
DISPLAY INVISIBLE (8625 3025);
FORCEPROP 0 LAST $SEC 1
J 0
(8625 3025);
DISPLAY 0.680851 (8625 3025);
PAINT MONO (8625 3025);
DISPLAY INVISIBLE (8625 3025);
FORCEPROP 0 LAST CDS_SEC 1
J 0
(8625 3025);
DISPLAY 1.021277 (8625 3025);
DISPLAY INVISIBLE (8625 3025);
FORCEADD Q_RES..1
(8675 2725);
FORCEPROP 1 LAST PART_NUMBER CS00002JB13
J 0
(8625 2775);
DISPLAY 0.404255 (8625 2775);
DISPLAY INVISIBLE (8625 2775);
FORCEPROP 1 LAST VALUE 0
J 2
(8825 2725);
DISPLAY 0.510638 (8825 2725);
FORCEPROP 1 LAST TOLERANCE 5%
J 0
(8850 2725);
DISPLAY 0.510638 (8850 2725);
FORCEPROP 1 LAST MATERIAL CHIP
J 0
(8925 2725);
DISPLAY 0.510638 (8925 2725);
FORCEPROP 1 LAST $LOCATION R3517
J 0
(8450 2725);
DISPLAY 0.638298 (8450 2725);
FORCEPROP 1 LASTPIN (8575 2725) $PN 1
J 0
(8587 2737);
DISPLAY 0.787234 (8587 2737);
PAINT MONO (8587 2737);
FORCEPROP 1 LASTPIN (8775 2725) $PN 2
J 0
(8737 2737);
DISPLAY 0.787234 (8737 2737);
PAINT MONO (8737 2737);
FORCEPROP 1 LAST PACK_TYPE 0402LF
J 0
(8925 2725);
DISPLAY 0.510638 (8925 2725);
DISPLAY INVISIBLE (8925 2725);
FORCEPROP 1 LAST WATTAGE 1/16W
J 2
(8850 2800);
DISPLAY 0.404255 (8850 2800);
DISPLAY INVISIBLE (8850 2800);
FORCEPROP 1 LAST PATH I128
J 0
(8625 2875);
DISPLAY 0.978723 (8625 2875);
PAINT WHITE (8625 2875);
DISPLAY INVISIBLE (8625 2875);
FORCEPROP 2 LAST CDS_LIB pure_quanta
J 0
(8675 2725);
DISPLAY INVISIBLE (8675 2725);
FORCEPROP 0 LAST CDS_LOCATION R3517
J 0
(8625 2825);
DISPLAY 1.021277 (8625 2825);
DISPLAY INVISIBLE (8625 2825);
FORCEPROP 0 LAST $SEC 1
J 0
(8625 2825);
DISPLAY 0.680851 (8625 2825);
PAINT MONO (8625 2825);
DISPLAY INVISIBLE (8625 2825);
FORCEPROP 0 LAST CDS_SEC 1
J 0
(8625 2825);
DISPLAY 1.021277 (8625 2825);
DISPLAY INVISIBLE (8625 2825);
FORCEADD Q_RES..1
(8675 2525);
FORCEPROP 1 LAST PART_NUMBER CS00002JB13
J 0
(8625 2575);
DISPLAY 0.404255 (8625 2575);
DISPLAY INVISIBLE (8625 2575);
FORCEPROP 1 LAST MATERIAL CHIP
J 0
(8925 2525);
DISPLAY 0.510638 (8925 2525);
FORCEPROP 1 LAST TOLERANCE 5%
J 0
(8850 2525);
DISPLAY 0.510638 (8850 2525);
FORCEPROP 1 LAST VALUE 0
J 2
(8825 2525);
DISPLAY 0.510638 (8825 2525);
FORCEPROP 1 LAST $LOCATION R3518
J 0
(8450 2525);
DISPLAY 0.638298 (8450 2525);
FORCEPROP 1 LASTPIN (8575 2525) $PN 1
J 0
(8587 2537);
DISPLAY 0.787234 (8587 2537);
PAINT MONO (8587 2537);
FORCEPROP 1 LASTPIN (8775 2525) $PN 2
J 0
(8737 2537);
DISPLAY 0.787234 (8737 2537);
PAINT MONO (8737 2537);
FORCEPROP 1 LAST PACK_TYPE 0402LF
J 0
(8925 2525);
DISPLAY 0.510638 (8925 2525);
DISPLAY INVISIBLE (8925 2525);
FORCEPROP 1 LAST WATTAGE 1/16W
J 2
(8850 2600);
DISPLAY 0.404255 (8850 2600);
DISPLAY INVISIBLE (8850 2600);
FORCEPROP 1 LAST PATH I129
J 0
(8625 2675);
DISPLAY 0.978723 (8625 2675);
PAINT WHITE (8625 2675);
DISPLAY INVISIBLE (8625 2675);
FORCEPROP 2 LAST CDS_LIB pure_quanta
J 0
(8675 2525);
DISPLAY INVISIBLE (8675 2525);
FORCEPROP 0 LAST CDS_LOCATION R3518
J 0
(8625 2625);
DISPLAY 1.021277 (8625 2625);
DISPLAY INVISIBLE (8625 2625);
FORCEPROP 0 LAST $SEC 1
J 0
(8625 2625);
DISPLAY 0.680851 (8625 2625);
PAINT MONO (8625 2625);
DISPLAY INVISIBLE (8625 2625);
FORCEPROP 0 LAST CDS_SEC 1
J 0
(8625 2625);
DISPLAY 1.021277 (8625 2625);
DISPLAY INVISIBLE (8625 2625);
FORCEADD OFFPAGE..1
R 2
(9200 5550);
FORCEPROP 2 LAST $XR0 227 
J 0
(9386 5550);
DISPLAY 0.638298 (9386 5550);
PAINT MONO (9386 5550);
FORCEPROP 1 LAST OFFPAGE TRUE
J 2
(8875 5425);
DISPLAY 0.872340 (8875 5425);
PAINT GREEN (8875 5425);
DISPLAY INVISIBLE (8875 5425);
FORCEPROP 1 LAST COMMENT_BODY TRUE
J 2
(9075 5450);
DISPLAY 0.872340 (9075 5450);
PAINT GREEN (9075 5450);
DISPLAY INVISIBLE (9075 5450);
FORCEPROP 2 LAST PATH I130
J 0
(9375 5625);
DISPLAY 1.021277 (9375 5625);
DISPLAY INVISIBLE (9375 5625);
FORCEPROP 2 LAST CDS_LIB standard
J 0
(9200 5550);
DISPLAY INVISIBLE (9200 5550);
FORCEADD OFFPAGE..1
R 2
(9200 5450);
FORCEPROP 2 LAST $XR0 227 
J 0
(9386 5450);
DISPLAY 0.638298 (9386 5450);
PAINT MONO (9386 5450);
FORCEPROP 2 LAST CDS_LIB standard
J 0
(9200 5450);
DISPLAY INVISIBLE (9200 5450);
FORCEPROP 2 LAST PATH I131
J 0
(9375 5525);
DISPLAY 1.021277 (9375 5525);
DISPLAY INVISIBLE (9375 5525);
FORCEPROP 1 LAST OFFPAGE TRUE
J 2
(8875 5325);
DISPLAY 0.872340 (8875 5325);
PAINT GREEN (8875 5325);
DISPLAY INVISIBLE (8875 5325);
FORCEPROP 1 LAST COMMENT_BODY TRUE
J 2
(9075 5350);
DISPLAY 0.872340 (9075 5350);
PAINT GREEN (9075 5350);
DISPLAY INVISIBLE (9075 5350);
FORCEADD OFFPAGE..1
R 2
(9200 5350);
FORCEPROP 2 LAST $XR0 227 
J 0
(9386 5350);
DISPLAY 0.638298 (9386 5350);
PAINT MONO (9386 5350);
FORCEPROP 2 LAST CDS_LIB standard
J 0
(9200 5350);
DISPLAY INVISIBLE (9200 5350);
FORCEPROP 2 LAST PATH I132
J 0
(9375 5425);
DISPLAY 1.021277 (9375 5425);
DISPLAY INVISIBLE (9375 5425);
FORCEPROP 1 LAST OFFPAGE TRUE
J 2
(8875 5225);
DISPLAY 0.872340 (8875 5225);
PAINT GREEN (8875 5225);
DISPLAY INVISIBLE (8875 5225);
FORCEPROP 1 LAST COMMENT_BODY TRUE
J 2
(9075 5250);
DISPLAY 0.872340 (9075 5250);
PAINT GREEN (9075 5250);
DISPLAY INVISIBLE (9075 5250);
FORCEADD OFFPAGE..1
R 2
(9200 5250);
FORCEPROP 2 LAST $XR0 227 
J 0
(9386 5250);
DISPLAY 0.638298 (9386 5250);
PAINT MONO (9386 5250);
FORCEPROP 2 LAST CDS_LIB standard
J 0
(9200 5250);
DISPLAY INVISIBLE (9200 5250);
FORCEPROP 2 LAST PATH I133
J 0
(9375 5325);
DISPLAY 1.021277 (9375 5325);
DISPLAY INVISIBLE (9375 5325);
FORCEPROP 1 LAST COMMENT_BODY TRUE
J 2
(9075 5150);
DISPLAY 0.872340 (9075 5150);
PAINT GREEN (9075 5150);
DISPLAY INVISIBLE (9075 5150);
FORCEPROP 1 LAST OFFPAGE TRUE
J 2
(8875 5125);
DISPLAY 0.872340 (8875 5125);
PAINT GREEN (8875 5125);
DISPLAY INVISIBLE (8875 5125);
FORCEADD OFFPAGE..2
R 2
(6550 5350);
FORCEPROP 2 LAST $XR0 227 
J 0
(6265 5350);
DISPLAY 0.638298 (6265 5350);
PAINT MONO (6265 5350);
FORCEPROP 2 LAST PATH I134
J 2
(6350 5400);
DISPLAY 1.021277 (6350 5400);
DISPLAY INVISIBLE (6350 5400);
FORCEPROP 1 LAST OFFPAGE TRUE
J 2
(6225 5225);
DISPLAY 0.872340 (6225 5225);
DISPLAY INVISIBLE (6225 5225);
FORCEPROP 1 LAST COMMENT_BODY TRUE
J 2
(6595 5255);
DISPLAY 0.872340 (6595 5255);
PAINT GREEN (6595 5255);
DISPLAY INVISIBLE (6595 5255);
FORCEPROP 2 LAST CDS_LIB standard
J 2
(6550 5350);
DISPLAY INVISIBLE (6550 5350);
FORCEADD OFFPAGE..2
R 2
(6550 5450);
FORCEPROP 2 LAST $XR1 196 
J 0
(6145 5450);
DISPLAY 0.638298 (6145 5450);
PAINT MONO (6145 5450);
FORCEPROP 2 LAST $XR0 152 
J 0
(6265 5450);
DISPLAY 0.638298 (6265 5450);
PAINT MONO (6265 5450);
FORCEPROP 2 LAST PATH I135
J 2
(6100 5500);
DISPLAY 1.021277 (6100 5500);
DISPLAY INVISIBLE (6100 5500);
FORCEPROP 1 LAST OFFPAGE TRUE
J 2
(6225 5325);
DISPLAY 0.872340 (6225 5325);
DISPLAY INVISIBLE (6225 5325);
FORCEPROP 1 LAST COMMENT_BODY TRUE
J 2
(6595 5355);
DISPLAY 0.872340 (6595 5355);
PAINT GREEN (6595 5355);
DISPLAY INVISIBLE (6595 5355);
FORCEPROP 2 LAST CDS_LIB standard
J 2
(6550 5450);
DISPLAY INVISIBLE (6550 5450);
FORCEADD OFFPAGE..2
(9925 2200);
FORCEPROP 2 LAST $XR0 227 
J 0
(10114 2200);
DISPLAY 0.638298 (10114 2200);
PAINT MONO (10114 2200);
FORCEPROP 1 LAST COMMENT_BODY TRUE
J 0
(9880 2105);
DISPLAY 0.872340 (9880 2105);
PAINT PEACH (9880 2105);
DISPLAY INVISIBLE (9880 2105);
FORCEPROP 1 LAST OFFPAGE TRUE
J 0
(10250 2075);
DISPLAY 0.872340 (10250 2075);
PAINT GREEN (10250 2075);
DISPLAY INVISIBLE (10250 2075);
FORCEPROP 2 LAST CDS_LIB standard
J 0
(9925 2200);
PAINT MONO (9925 2200);
DISPLAY INVISIBLE (9925 2200);
FORCEPROP 2 LAST PATH I136
J 0
(10125 2250);
DISPLAY 1.021277 (10125 2250);
DISPLAY INVISIBLE (10125 2250);
FORCEADD Q_RES..1
(8650 2200);
FORCEPROP 1 LAST PART_NUMBER CS00002JB13
J 0
(8600 2250);
DISPLAY 0.404255 (8600 2250);
DISPLAY INVISIBLE (8600 2250);
FORCEPROP 1 LAST MATERIAL CHIP
J 0
(8900 2200);
DISPLAY 0.510638 (8900 2200);
FORCEPROP 1 LAST TOLERANCE 5%
J 0
(8825 2200);
DISPLAY 0.510638 (8825 2200);
FORCEPROP 1 LAST VALUE 0
J 2
(8800 2200);
DISPLAY 0.510638 (8800 2200);
FORCEPROP 1 LAST $LOCATION R4728
J 0
(8400 2200);
DISPLAY 0.808511 (8400 2200);
FORCEPROP 1 LASTPIN (8550 2200) $PN 1
J 0
(8562 2212);
DISPLAY 0.787234 (8562 2212);
PAINT MONO (8562 2212);
FORCEPROP 1 LASTPIN (8750 2200) $PN 2
J 0
(8712 2212);
DISPLAY 0.787234 (8712 2212);
PAINT MONO (8712 2212);
FORCEPROP 1 LAST WATTAGE 1/16W
J 2
(8825 2275);
DISPLAY 0.404255 (8825 2275);
DISPLAY INVISIBLE (8825 2275);
FORCEPROP 1 LAST PACK_TYPE 0402LF
J 0
(8900 2200);
DISPLAY 0.510638 (8900 2200);
DISPLAY INVISIBLE (8900 2200);
FORCEPROP 2 LAST CDS_LIB pure_quanta
J 0
(8650 2200);
DISPLAY INVISIBLE (8650 2200);
FORCEPROP 1 LAST PATH I137
J 0
(8600 2350);
DISPLAY 0.978723 (8600 2350);
PAINT WHITE (8600 2350);
DISPLAY INVISIBLE (8600 2350);
FORCEPROP 0 LAST CDS_LOCATION R4728
J 0
(8900 2225);
DISPLAY 1.021277 (8900 2225);
DISPLAY INVISIBLE (8900 2225);
FORCEPROP 0 LAST $SEC 1
J 0
(8900 2225);
DISPLAY 0.680851 (8900 2225);
PAINT MONO (8900 2225);
DISPLAY INVISIBLE (8900 2225);
FORCEPROP 0 LAST CDS_SEC 1
J 0
(8900 2225);
DISPLAY 1.021277 (8900 2225);
DISPLAY INVISIBLE (8900 2225);
FORCEADD OFFPAGE..1
(7425 2200);
FORCEPROP 2 LAST $XR1 215 
J 0
(7053 2200);
DISPLAY 0.638298 (7053 2200);
PAINT MONO (7053 2200);
FORCEPROP 2 LAST $XR0 144 
J 0
(7173 2200);
DISPLAY 0.638298 (7173 2200);
PAINT MONO (7173 2200);
FORCEPROP 1 LAST OFFPAGE TRUE
J 0
(7750 2075);
DISPLAY 0.872340 (7750 2075);
DISPLAY INVISIBLE (7750 2075);
FORCEPROP 1 LAST COMMENT_BODY TRUE
J 0
(7550 2100);
DISPLAY 1.170213 (7550 2100);
PAINT GREEN (7550 2100);
DISPLAY INVISIBLE (7550 2100);
FORCEPROP 2 LAST CDS_LIB standard
J 0
(7425 2200);
DISPLAY INVISIBLE (7425 2200);
FORCEPROP 2 LAST PATH I138
J 0
(7150 2250);
DISPLAY 1.021277 (7150 2250);
DISPLAY INVISIBLE (7150 2250);
FORCEADD OFFPAGE..2
(9925 2050);
FORCEPROP 2 LAST $XR0 227 
J 0
(10114 2050);
DISPLAY 0.638298 (10114 2050);
PAINT MONO (10114 2050);
FORCEPROP 2 LAST CDS_LIB standard
J 0
(9925 2050);
PAINT MONO (9925 2050);
DISPLAY INVISIBLE (9925 2050);
FORCEPROP 1 LAST OFFPAGE TRUE
J 0
(10250 1925);
DISPLAY 0.872340 (10250 1925);
PAINT GREEN (10250 1925);
DISPLAY INVISIBLE (10250 1925);
FORCEPROP 1 LAST COMMENT_BODY TRUE
J 0
(9880 1955);
DISPLAY 0.872340 (9880 1955);
PAINT PEACH (9880 1955);
DISPLAY INVISIBLE (9880 1955);
FORCEPROP 2 LAST PATH I139
J 0
(10125 2100);
DISPLAY 1.021277 (10125 2100);
DISPLAY INVISIBLE (10125 2100);
FORCEADD Q_RES..1
(8650 2050);
FORCEPROP 1 LAST PART_NUMBER CS00002JB13
J 0
(8600 2100);
DISPLAY 0.404255 (8600 2100);
DISPLAY INVISIBLE (8600 2100);
FORCEPROP 1 LAST VALUE 0
J 2
(8800 2050);
DISPLAY 0.510638 (8800 2050);
FORCEPROP 1 LAST MATERIAL CHIP
J 0
(8900 2050);
DISPLAY 0.510638 (8900 2050);
FORCEPROP 1 LAST TOLERANCE 5%
J 0
(8825 2050);
DISPLAY 0.510638 (8825 2050);
FORCEPROP 1 LAST $LOCATION R4729
J 0
(8400 2050);
DISPLAY 0.808511 (8400 2050);
FORCEPROP 1 LASTPIN (8550 2050) $PN 1
J 0
(8562 2062);
DISPLAY 0.787234 (8562 2062);
PAINT MONO (8562 2062);
FORCEPROP 1 LASTPIN (8750 2050) $PN 2
J 0
(8712 2062);
DISPLAY 0.787234 (8712 2062);
PAINT MONO (8712 2062);
FORCEPROP 2 LAST CDS_LIB pure_quanta
J 0
(8650 2050);
DISPLAY INVISIBLE (8650 2050);
FORCEPROP 1 LAST PACK_TYPE 0402LF
J 0
(8900 2050);
DISPLAY 0.510638 (8900 2050);
DISPLAY INVISIBLE (8900 2050);
FORCEPROP 1 LAST WATTAGE 1/16W
J 2
(8825 2125);
DISPLAY 0.404255 (8825 2125);
DISPLAY INVISIBLE (8825 2125);
FORCEPROP 1 LAST PATH I140
J 0
(8600 2200);
DISPLAY 0.978723 (8600 2200);
PAINT WHITE (8600 2200);
DISPLAY INVISIBLE (8600 2200);
FORCEPROP 0 LAST CDS_LOCATION R4729
J 0
(8900 2075);
DISPLAY 1.021277 (8900 2075);
DISPLAY INVISIBLE (8900 2075);
FORCEPROP 0 LAST $SEC 1
J 0
(8900 2075);
DISPLAY 0.680851 (8900 2075);
PAINT MONO (8900 2075);
DISPLAY INVISIBLE (8900 2075);
FORCEPROP 0 LAST CDS_SEC 1
J 0
(8900 2075);
DISPLAY 1.021277 (8900 2075);
DISPLAY INVISIBLE (8900 2075);
FORCEADD OFFPAGE..1
(7425 2050);
FORCEPROP 2 LAST $XR1 213 
J 0
(7053 2050);
DISPLAY 0.638298 (7053 2050);
PAINT MONO (7053 2050);
FORCEPROP 2 LAST $XR0 147 
J 0
(7173 2050);
DISPLAY 0.638298 (7173 2050);
PAINT MONO (7173 2050);
FORCEPROP 2 LAST CDS_LIB standard
J 0
(7425 2050);
DISPLAY INVISIBLE (7425 2050);
FORCEPROP 1 LAST COMMENT_BODY TRUE
J 0
(7550 1950);
DISPLAY 1.170213 (7550 1950);
PAINT GREEN (7550 1950);
DISPLAY INVISIBLE (7550 1950);
FORCEPROP 1 LAST OFFPAGE TRUE
J 0
(7750 1925);
DISPLAY 0.872340 (7750 1925);
DISPLAY INVISIBLE (7750 1925);
FORCEPROP 2 LAST PATH I141
J 0
(7150 2100);
DISPLAY 1.021277 (7150 2100);
DISPLAY INVISIBLE (7150 2100);
FORCEADD OFFPAGE..1
(6300 5050);
FORCEPROP 2 LAST $XR0 227 
J 0
(6048 5050);
DISPLAY 0.638298 (6048 5050);
PAINT MONO (6048 5050);
FORCEPROP 2 LAST CDS_LIB standard
J 2
(6300 5050);
DISPLAY INVISIBLE (6300 5050);
FORCEPROP 2 LAST PATH I142
J 2
(6125 5125);
DISPLAY 1.021277 (6125 5125);
DISPLAY INVISIBLE (6125 5125);
FORCEPROP 1 LAST OFFPAGE TRUE
J 0
(6625 4925);
DISPLAY 0.872340 (6625 4925);
PAINT GREEN (6625 4925);
DISPLAY INVISIBLE (6625 4925);
FORCEPROP 1 LAST COMMENT_BODY TRUE
J 0
(6425 4950);
DISPLAY 0.872340 (6425 4950);
PAINT GREEN (6425 4950);
DISPLAY INVISIBLE (6425 4950);
FORCEADD OFFPAGE..1
(6300 4950);
FORCEPROP 2 LAST $XR0 227 
J 0
(6048 4950);
DISPLAY 0.638298 (6048 4950);
PAINT MONO (6048 4950);
FORCEPROP 2 LAST CDS_LIB standard
J 0
(6300 4950);
DISPLAY INVISIBLE (6300 4950);
FORCEPROP 2 LAST PATH I143
J 0
(6350 5025);
DISPLAY 1.021277 (6350 5025);
DISPLAY INVISIBLE (6350 5025);
FORCEPROP 1 LAST OFFPAGE TRUE
J 0
(6625 4825);
DISPLAY 0.872340 (6625 4825);
PAINT GREEN (6625 4825);
DISPLAY INVISIBLE (6625 4825);
FORCEPROP 1 LAST COMMENT_BODY TRUE
J 0
(6425 4850);
DISPLAY 0.872340 (6425 4850);
PAINT GREEN (6425 4850);
DISPLAY INVISIBLE (6425 4850);
FORCEADD Q_RES..1
(8650 1900);
FORCEPROP 1 LAST PART_NUMBER CS00002JB13
J 0
(8600 1950);
DISPLAY 0.404255 (8600 1950);
DISPLAY INVISIBLE (8600 1950);
FORCEPROP 1 LAST MATERIAL CHIP
J 0
(8900 1900);
DISPLAY 0.510638 (8900 1900);
FORCEPROP 1 LAST TOLERANCE 5%
J 0
(8825 1900);
DISPLAY 0.510638 (8825 1900);
FORCEPROP 1 LAST VALUE 0
J 2
(8800 1900);
DISPLAY 0.510638 (8800 1900);
FORCEPROP 1 LAST $LOCATION R4734
J 0
(8400 1900);
DISPLAY 0.808511 (8400 1900);
FORCEPROP 1 LASTPIN (8550 1900) $PN 1
J 0
(8562 1912);
DISPLAY 0.787234 (8562 1912);
PAINT MONO (8562 1912);
FORCEPROP 1 LASTPIN (8750 1900) $PN 2
J 0
(8712 1912);
DISPLAY 0.787234 (8712 1912);
PAINT MONO (8712 1912);
FORCEPROP 1 LAST WATTAGE 1/16W
J 2
(8825 1975);
DISPLAY 0.404255 (8825 1975);
DISPLAY INVISIBLE (8825 1975);
FORCEPROP 1 LAST PACK_TYPE 0402LF
J 0
(8900 1900);
DISPLAY 0.510638 (8900 1900);
DISPLAY INVISIBLE (8900 1900);
FORCEPROP 1 LAST PATH I144
J 0
(8600 2050);
DISPLAY 0.978723 (8600 2050);
PAINT WHITE (8600 2050);
DISPLAY INVISIBLE (8600 2050);
FORCEPROP 2 LAST CDS_LIB pure_quanta
J 0
(8650 1900);
DISPLAY INVISIBLE (8650 1900);
FORCEPROP 0 LAST CDS_LOCATION R4734
J 0
(8900 1925);
DISPLAY 1.021277 (8900 1925);
DISPLAY INVISIBLE (8900 1925);
FORCEPROP 0 LAST $SEC 1
J 0
(8900 1925);
DISPLAY 0.680851 (8900 1925);
PAINT MONO (8900 1925);
DISPLAY INVISIBLE (8900 1925);
FORCEPROP 0 LAST CDS_SEC 1
J 0
(8900 1925);
DISPLAY 1.021277 (8900 1925);
DISPLAY INVISIBLE (8900 1925);
FORCEADD OFFPAGE..2
(9925 1900);
FORCEPROP 2 LAST $XR0 227 
J 0
(10114 1900);
DISPLAY 0.638298 (10114 1900);
PAINT MONO (10114 1900);
FORCEPROP 1 LAST COMMENT_BODY TRUE
J 0
(9880 1805);
DISPLAY 0.872340 (9880 1805);
PAINT PEACH (9880 1805);
DISPLAY INVISIBLE (9880 1805);
FORCEPROP 1 LAST OFFPAGE TRUE
J 0
(10250 1775);
DISPLAY 0.872340 (10250 1775);
PAINT GREEN (10250 1775);
DISPLAY INVISIBLE (10250 1775);
FORCEPROP 2 LAST PATH I145
J 0
(10125 1950);
DISPLAY 1.021277 (10125 1950);
DISPLAY INVISIBLE (10125 1950);
FORCEPROP 2 LAST CDS_LIB standard
J 0
(9925 1900);
PAINT MONO (9925 1900);
DISPLAY INVISIBLE (9925 1900);
FORCEADD OFFPAGE..1
(7425 1900);
FORCEPROP 2 LAST $XR1 215 
J 0
(7053 1900);
DISPLAY 0.638298 (7053 1900);
PAINT MONO (7053 1900);
FORCEPROP 2 LAST $XR0 146 
J 0
(7173 1900);
DISPLAY 0.638298 (7173 1900);
PAINT MONO (7173 1900);
FORCEPROP 1 LAST OFFPAGE TRUE
J 0
(7750 1775);
DISPLAY 0.872340 (7750 1775);
DISPLAY INVISIBLE (7750 1775);
FORCEPROP 1 LAST COMMENT_BODY TRUE
J 0
(7550 1800);
DISPLAY 1.170213 (7550 1800);
PAINT GREEN (7550 1800);
DISPLAY INVISIBLE (7550 1800);
FORCEPROP 2 LAST PATH I146
J 0
(7150 1950);
DISPLAY 1.021277 (7150 1950);
DISPLAY INVISIBLE (7150 1950);
FORCEPROP 2 LAST CDS_LIB standard
J 0
(7425 1900);
DISPLAY INVISIBLE (7425 1900);
FORCEADD OFFPAGE..1
(6300 4850);
FORCEPROP 2 LAST $XR0 227 
J 0
(6048 4850);
DISPLAY 0.638298 (6048 4850);
PAINT MONO (6048 4850);
FORCEPROP 2 LAST CDS_LIB standard
J 0
(6300 4850);
DISPLAY INVISIBLE (6300 4850);
FORCEPROP 2 LAST PATH I147
J 0
(6350 4925);
DISPLAY 1.021277 (6350 4925);
DISPLAY INVISIBLE (6350 4925);
FORCEPROP 1 LAST OFFPAGE TRUE
J 0
(6625 4725);
DISPLAY 0.872340 (6625 4725);
PAINT GREEN (6625 4725);
DISPLAY INVISIBLE (6625 4725);
FORCEPROP 1 LAST COMMENT_BODY TRUE
J 0
(6425 4750);
DISPLAY 0.872340 (6425 4750);
PAINT GREEN (6425 4750);
DISPLAY INVISIBLE (6425 4750);
FORCEADD Q_RES..1
(8650 1750);
FORCEPROP 1 LAST PART_NUMBER CS00002JB13
J 0
(8600 1800);
DISPLAY 0.404255 (8600 1800);
DISPLAY INVISIBLE (8600 1800);
FORCEPROP 1 LAST MATERIAL CHIP
J 0
(8900 1750);
DISPLAY 0.510638 (8900 1750);
FORCEPROP 1 LAST TOLERANCE 5%
J 0
(8825 1750);
DISPLAY 0.510638 (8825 1750);
FORCEPROP 1 LAST VALUE 0
J 2
(8800 1750);
DISPLAY 0.510638 (8800 1750);
FORCEPROP 1 LAST $LOCATION R4735
J 0
(8425 1750);
DISPLAY 0.787234 (8425 1750);
FORCEPROP 1 LASTPIN (8550 1750) $PN 1
J 0
(8562 1762);
DISPLAY 0.787234 (8562 1762);
PAINT MONO (8562 1762);
FORCEPROP 1 LASTPIN (8750 1750) $PN 2
J 0
(8712 1762);
DISPLAY 0.787234 (8712 1762);
PAINT MONO (8712 1762);
FORCEPROP 1 LAST PATH I148
J 0
(8600 1900);
DISPLAY 0.978723 (8600 1900);
PAINT WHITE (8600 1900);
DISPLAY INVISIBLE (8600 1900);
FORCEPROP 1 LAST WATTAGE 1/16W
J 2
(8825 1825);
DISPLAY 0.404255 (8825 1825);
DISPLAY INVISIBLE (8825 1825);
FORCEPROP 1 LAST PACK_TYPE 0402LF
J 0
(8900 1750);
DISPLAY 0.510638 (8900 1750);
DISPLAY INVISIBLE (8900 1750);
FORCEPROP 2 LAST CDS_LIB pure_quanta
J 0
(8650 1750);
DISPLAY INVISIBLE (8650 1750);
FORCEPROP 0 LAST CDS_LOCATION R4735
J 0
(8600 1850);
DISPLAY 1.021277 (8600 1850);
DISPLAY INVISIBLE (8600 1850);
FORCEPROP 0 LAST $SEC 1
J 0
(8600 1850);
DISPLAY 0.680851 (8600 1850);
PAINT MONO (8600 1850);
DISPLAY INVISIBLE (8600 1850);
FORCEPROP 0 LAST CDS_SEC 1
J 0
(8600 1850);
DISPLAY 1.021277 (8600 1850);
DISPLAY INVISIBLE (8600 1850);
FORCEADD OFFPAGE..2
(9925 1750);
FORCEPROP 2 LAST $XR0 227 
J 0
(10114 1750);
DISPLAY 0.638298 (10114 1750);
PAINT MONO (10114 1750);
FORCEPROP 2 LAST CDS_LIB standard
J 0
(9925 1750);
DISPLAY INVISIBLE (9925 1750);
FORCEPROP 1 LAST COMMENT_BODY TRUE
J 0
(9880 1655);
DISPLAY 0.872340 (9880 1655);
PAINT PEACH (9880 1655);
DISPLAY INVISIBLE (9880 1655);
FORCEPROP 1 LAST OFFPAGE TRUE
J 0
(10250 1625);
DISPLAY 0.872340 (10250 1625);
PAINT GREEN (10250 1625);
DISPLAY INVISIBLE (10250 1625);
FORCEPROP 2 LAST PATH I149
J 0
(10100 1825);
DISPLAY 1.021277 (10100 1825);
DISPLAY INVISIBLE (10100 1825);
FORCEADD OFFPAGE..1
(7425 1750);
FORCEPROP 2 LAST $XR0 144 
J 0
(7173 1750);
DISPLAY 0.638298 (7173 1750);
PAINT MONO (7173 1750);
FORCEPROP 2 LAST CDS_LIB standard
J 0
(7425 1750);
DISPLAY INVISIBLE (7425 1750);
FORCEPROP 1 LAST OFFPAGE TRUE
J 0
(7750 1625);
DISPLAY 0.872340 (7750 1625);
DISPLAY INVISIBLE (7750 1625);
FORCEPROP 1 LAST COMMENT_BODY TRUE
J 0
(7550 1650);
DISPLAY 1.170213 (7550 1650);
PAINT GREEN (7550 1650);
DISPLAY INVISIBLE (7550 1650);
FORCEPROP 2 LAST PATH I150
J 0
(7475 1825);
DISPLAY 1.021277 (7475 1825);
DISPLAY INVISIBLE (7475 1825);
FORCEADD OFFPAGE..1
(6300 4750);
FORCEPROP 2 LAST $XR0 227 
J 0
(6048 4750);
DISPLAY 0.638298 (6048 4750);
PAINT MONO (6048 4750);
FORCEPROP 1 LAST COMMENT_BODY TRUE
J 0
(6425 4650);
DISPLAY 0.872340 (6425 4650);
PAINT GREEN (6425 4650);
DISPLAY INVISIBLE (6425 4650);
FORCEPROP 1 LAST OFFPAGE TRUE
J 0
(6625 4625);
DISPLAY 0.872340 (6625 4625);
PAINT GREEN (6625 4625);
DISPLAY INVISIBLE (6625 4625);
FORCEPROP 2 LAST PATH I151
J 0
(6350 4825);
DISPLAY 1.021277 (6350 4825);
DISPLAY INVISIBLE (6350 4825);
FORCEPROP 2 LAST CDS_LIB standard
J 0
(6300 4750);
DISPLAY INVISIBLE (6300 4750);
FORCEADD OFFPAGE..2
(9925 1600);
FORCEPROP 2 LAST $XR0 227 
J 0
(10114 1600);
DISPLAY 0.638298 (10114 1600);
PAINT MONO (10114 1600);
FORCEPROP 2 LAST CDS_LIB standard
J 0
(9925 1600);
DISPLAY INVISIBLE (9925 1600);
FORCEPROP 2 LAST PATH I152
J 0
(10100 1675);
DISPLAY 1.021277 (10100 1675);
DISPLAY INVISIBLE (10100 1675);
FORCEPROP 1 LAST OFFPAGE TRUE
J 0
(10250 1475);
DISPLAY 0.872340 (10250 1475);
PAINT GREEN (10250 1475);
DISPLAY INVISIBLE (10250 1475);
FORCEPROP 1 LAST COMMENT_BODY TRUE
J 0
(9880 1505);
DISPLAY 0.872340 (9880 1505);
PAINT PEACH (9880 1505);
DISPLAY INVISIBLE (9880 1505);
FORCEADD Q_RES..1
(8650 1600);
FORCEPROP 1 LAST PART_NUMBER CS00002JB13
J 0
(8600 1650);
DISPLAY 0.404255 (8600 1650);
DISPLAY INVISIBLE (8600 1650);
FORCEPROP 1 LAST MATERIAL CHIP
J 0
(8900 1600);
DISPLAY 0.510638 (8900 1600);
FORCEPROP 1 LAST TOLERANCE 5%
J 0
(8825 1600);
DISPLAY 0.510638 (8825 1600);
FORCEPROP 1 LAST VALUE 0
J 2
(8800 1600);
DISPLAY 0.510638 (8800 1600);
FORCEPROP 1 LAST $LOCATION R4736
J 0
(8425 1600);
DISPLAY 0.787234 (8425 1600);
FORCEPROP 1 LASTPIN (8550 1600) $PN 1
J 0
(8562 1612);
DISPLAY 0.787234 (8562 1612);
PAINT MONO (8562 1612);
FORCEPROP 1 LASTPIN (8750 1600) $PN 2
J 0
(8712 1612);
DISPLAY 0.787234 (8712 1612);
PAINT MONO (8712 1612);
FORCEPROP 1 LAST PACK_TYPE 0402LF
J 0
(8900 1600);
DISPLAY 0.510638 (8900 1600);
DISPLAY INVISIBLE (8900 1600);
FORCEPROP 1 LAST WATTAGE 1/16W
J 2
(8825 1675);
DISPLAY 0.404255 (8825 1675);
DISPLAY INVISIBLE (8825 1675);
FORCEPROP 1 LAST PATH I153
J 0
(8600 1750);
DISPLAY 0.978723 (8600 1750);
PAINT WHITE (8600 1750);
DISPLAY INVISIBLE (8600 1750);
FORCEPROP 2 LAST CDS_LIB pure_quanta
J 0
(8650 1600);
DISPLAY INVISIBLE (8650 1600);
FORCEPROP 0 LAST CDS_LOCATION R4736
J 0
(8600 1700);
DISPLAY 1.021277 (8600 1700);
DISPLAY INVISIBLE (8600 1700);
FORCEPROP 0 LAST $SEC 1
J 0
(8600 1700);
DISPLAY 0.680851 (8600 1700);
PAINT MONO (8600 1700);
DISPLAY INVISIBLE (8600 1700);
FORCEPROP 0 LAST CDS_SEC 1
J 0
(8600 1700);
DISPLAY 1.021277 (8600 1700);
DISPLAY INVISIBLE (8600 1700);
FORCEADD OFFPAGE..1
(7425 1600);
FORCEPROP 2 LAST $XR1 215 
J 0
(7053 1600);
DISPLAY 0.638298 (7053 1600);
PAINT MONO (7053 1600);
FORCEPROP 2 LAST $XR0 146 
J 0
(7173 1600);
DISPLAY 0.638298 (7173 1600);
PAINT MONO (7173 1600);
FORCEPROP 2 LAST CDS_LIB standard
J 0
(7425 1600);
DISPLAY INVISIBLE (7425 1600);
FORCEPROP 2 LAST PATH I154
J 0
(7475 1675);
DISPLAY 1.021277 (7475 1675);
DISPLAY INVISIBLE (7475 1675);
FORCEPROP 1 LAST COMMENT_BODY TRUE
J 0
(7550 1500);
DISPLAY 1.170213 (7550 1500);
PAINT GREEN (7550 1500);
DISPLAY INVISIBLE (7550 1500);
FORCEPROP 1 LAST OFFPAGE TRUE
J 0
(7750 1475);
DISPLAY 0.872340 (7750 1475);
DISPLAY INVISIBLE (7750 1475);
FORCEADD OFFPAGE..1
R 2
(9200 5750);
FORCEPROP 2 LAST $XR0 227 
J 0
(9386 5750);
DISPLAY 0.638298 (9386 5750);
PAINT MONO (9386 5750);
FORCEPROP 2 LAST CDS_LIB standard
J 0
(9200 5750);
DISPLAY INVISIBLE (9200 5750);
FORCEPROP 2 LAST PATH I155
J 0
(9375 5825);
DISPLAY 1.021277 (9375 5825);
DISPLAY INVISIBLE (9375 5825);
FORCEPROP 1 LAST OFFPAGE TRUE
J 2
(8875 5625);
DISPLAY 0.872340 (8875 5625);
PAINT GREEN (8875 5625);
DISPLAY INVISIBLE (8875 5625);
FORCEPROP 1 LAST COMMENT_BODY TRUE
J 2
(9075 5650);
DISPLAY 0.872340 (9075 5650);
PAINT GREEN (9075 5650);
DISPLAY INVISIBLE (9075 5650);
FORCEADD Q_RES..1
(8650 1450);
FORCEPROP 1 LAST PART_NUMBER CS00002JB13
J 0
(8600 1500);
DISPLAY 0.404255 (8600 1500);
DISPLAY INVISIBLE (8600 1500);
FORCEPROP 1 LAST TOLERANCE 5%
J 0
(8825 1450);
DISPLAY 0.510638 (8825 1450);
FORCEPROP 1 LAST MATERIAL CHIP
J 0
(8900 1450);
DISPLAY 0.510638 (8900 1450);
FORCEPROP 1 LAST VALUE 0
J 2
(8800 1450);
DISPLAY 0.510638 (8800 1450);
FORCEPROP 1 LAST $LOCATION R4741
J 0
(8425 1450);
DISPLAY 0.787234 (8425 1450);
FORCEPROP 1 LASTPIN (8550 1450) $PN 1
J 0
(8562 1462);
DISPLAY 0.787234 (8562 1462);
PAINT MONO (8562 1462);
FORCEPROP 1 LASTPIN (8750 1450) $PN 2
J 0
(8712 1462);
DISPLAY 0.787234 (8712 1462);
PAINT MONO (8712 1462);
FORCEPROP 1 LAST PACK_TYPE 0402LF
J 0
(8900 1450);
DISPLAY 0.510638 (8900 1450);
DISPLAY INVISIBLE (8900 1450);
FORCEPROP 1 LAST WATTAGE 1/16W
J 2
(8825 1525);
DISPLAY 0.404255 (8825 1525);
DISPLAY INVISIBLE (8825 1525);
FORCEPROP 1 LAST PATH I156
J 0
(8600 1600);
DISPLAY 0.978723 (8600 1600);
PAINT WHITE (8600 1600);
DISPLAY INVISIBLE (8600 1600);
FORCEPROP 2 LAST CDS_LIB pure_quanta
J 0
(8650 1450);
DISPLAY INVISIBLE (8650 1450);
FORCEPROP 0 LAST CDS_LOCATION R4741
J 0
(8600 1550);
DISPLAY 1.021277 (8600 1550);
DISPLAY INVISIBLE (8600 1550);
FORCEPROP 0 LAST $SEC 1
J 0
(8600 1550);
DISPLAY 0.680851 (8600 1550);
PAINT MONO (8600 1550);
DISPLAY INVISIBLE (8600 1550);
FORCEPROP 0 LAST CDS_SEC 1
J 0
(8600 1550);
DISPLAY 1.021277 (8600 1550);
DISPLAY INVISIBLE (8600 1550);
FORCEADD OFFPAGE..1
(7425 1450);
FORCEPROP 2 LAST $XR0 144 
J 0
(7173 1450);
DISPLAY 0.638298 (7173 1450);
PAINT MONO (7173 1450);
FORCEPROP 1 LAST OFFPAGE TRUE
J 0
(7750 1325);
DISPLAY 0.872340 (7750 1325);
DISPLAY INVISIBLE (7750 1325);
FORCEPROP 1 LAST COMMENT_BODY TRUE
J 0
(7550 1350);
DISPLAY 1.170213 (7550 1350);
PAINT GREEN (7550 1350);
DISPLAY INVISIBLE (7550 1350);
FORCEPROP 2 LAST PATH I157
J 0
(7475 1525);
DISPLAY 1.021277 (7475 1525);
DISPLAY INVISIBLE (7475 1525);
FORCEPROP 2 LAST CDS_LIB standard
J 0
(7425 1450);
DISPLAY INVISIBLE (7425 1450);
FORCEADD OFFPAGE..2
(9925 1450);
FORCEPROP 2 LAST $XR0 227 
J 0
(10114 1450);
DISPLAY 0.638298 (10114 1450);
PAINT MONO (10114 1450);
FORCEPROP 1 LAST OFFPAGE TRUE
J 0
(10250 1325);
DISPLAY 0.872340 (10250 1325);
PAINT GREEN (10250 1325);
DISPLAY INVISIBLE (10250 1325);
FORCEPROP 1 LAST COMMENT_BODY TRUE
J 0
(9880 1355);
DISPLAY 0.872340 (9880 1355);
PAINT PEACH (9880 1355);
DISPLAY INVISIBLE (9880 1355);
FORCEPROP 2 LAST PATH I158
J 0
(10100 1525);
DISPLAY 1.021277 (10100 1525);
DISPLAY INVISIBLE (10100 1525);
FORCEPROP 2 LAST CDS_LIB standard
J 0
(9925 1450);
DISPLAY INVISIBLE (9925 1450);
FORCEADD OFFPAGE..1
R 2
(9200 5650);
FORCEPROP 2 LAST $XR0 227 
J 0
(9386 5650);
DISPLAY 0.638298 (9386 5650);
PAINT MONO (9386 5650);
FORCEPROP 1 LAST OFFPAGE TRUE
J 2
(8875 5525);
DISPLAY 0.872340 (8875 5525);
PAINT GREEN (8875 5525);
DISPLAY INVISIBLE (8875 5525);
FORCEPROP 1 LAST COMMENT_BODY TRUE
J 2
(9075 5550);
DISPLAY 0.872340 (9075 5550);
PAINT GREEN (9075 5550);
DISPLAY INVISIBLE (9075 5550);
FORCEPROP 2 LAST PATH I159
J 0
(9375 5725);
DISPLAY 1.021277 (9375 5725);
DISPLAY INVISIBLE (9375 5725);
FORCEPROP 2 LAST CDS_LIB standard
J 0
(9200 5650);
DISPLAY INVISIBLE (9200 5650);
FORCEADD OFFPAGE..1
(7425 1300);
FORCEPROP 2 LAST $XR1 215 
J 0
(7053 1300);
DISPLAY 0.638298 (7053 1300);
PAINT MONO (7053 1300);
FORCEPROP 2 LAST $XR0 146 
J 0
(7173 1300);
DISPLAY 0.638298 (7173 1300);
PAINT MONO (7173 1300);
FORCEPROP 1 LAST OFFPAGE TRUE
J 0
(7750 1175);
DISPLAY 0.872340 (7750 1175);
DISPLAY INVISIBLE (7750 1175);
FORCEPROP 1 LAST COMMENT_BODY TRUE
J 0
(7550 1200);
DISPLAY 1.170213 (7550 1200);
PAINT GREEN (7550 1200);
DISPLAY INVISIBLE (7550 1200);
FORCEPROP 2 LAST PATH I160
J 0
(7475 1375);
DISPLAY 1.021277 (7475 1375);
DISPLAY INVISIBLE (7475 1375);
FORCEPROP 2 LAST CDS_LIB standard
J 0
(7425 1300);
DISPLAY INVISIBLE (7425 1300);
FORCEADD Q_RES..1
(8650 1300);
FORCEPROP 1 LAST PART_NUMBER CS00002JB13
J 0
(8600 1350);
DISPLAY 0.404255 (8600 1350);
DISPLAY INVISIBLE (8600 1350);
FORCEPROP 1 LAST VALUE 0
J 2
(8800 1300);
DISPLAY 0.510638 (8800 1300);
FORCEPROP 1 LAST TOLERANCE 5%
J 0
(8825 1300);
DISPLAY 0.510638 (8825 1300);
FORCEPROP 1 LAST MATERIAL CHIP
J 0
(8900 1300);
DISPLAY 0.510638 (8900 1300);
FORCEPROP 1 LAST $LOCATION R4742
J 0
(8425 1300);
DISPLAY 0.638298 (8425 1300);
FORCEPROP 1 LASTPIN (8550 1300) $PN 1
J 0
(8562 1312);
DISPLAY 0.787234 (8562 1312);
PAINT MONO (8562 1312);
FORCEPROP 1 LASTPIN (8750 1300) $PN 2
J 0
(8712 1312);
DISPLAY 0.787234 (8712 1312);
PAINT MONO (8712 1312);
FORCEPROP 1 LAST PACK_TYPE 0402LF
J 0
(8900 1300);
DISPLAY 0.510638 (8900 1300);
DISPLAY INVISIBLE (8900 1300);
FORCEPROP 1 LAST WATTAGE 1/16W
J 2
(8825 1375);
DISPLAY 0.404255 (8825 1375);
DISPLAY INVISIBLE (8825 1375);
FORCEPROP 1 LAST PATH I161
J 0
(8600 1450);
DISPLAY 0.978723 (8600 1450);
PAINT WHITE (8600 1450);
DISPLAY INVISIBLE (8600 1450);
FORCEPROP 2 LAST CDS_LIB pure_quanta
J 0
(8650 1300);
DISPLAY INVISIBLE (8650 1300);
FORCEPROP 0 LAST CDS_LOCATION R4742
J 0
(8600 1400);
DISPLAY 1.021277 (8600 1400);
DISPLAY INVISIBLE (8600 1400);
FORCEPROP 0 LAST $SEC 1
J 0
(8600 1400);
DISPLAY 0.680851 (8600 1400);
PAINT MONO (8600 1400);
DISPLAY INVISIBLE (8600 1400);
FORCEPROP 0 LAST CDS_SEC 1
J 0
(8600 1400);
DISPLAY 1.021277 (8600 1400);
DISPLAY INVISIBLE (8600 1400);
FORCEADD OFFPAGE..2
(9925 1300);
FORCEPROP 2 LAST $XR0 227 
J 0
(10114 1300);
DISPLAY 0.638298 (10114 1300);
PAINT MONO (10114 1300);
FORCEPROP 1 LAST OFFPAGE TRUE
J 0
(10250 1175);
DISPLAY 0.872340 (10250 1175);
PAINT GREEN (10250 1175);
DISPLAY INVISIBLE (10250 1175);
FORCEPROP 1 LAST COMMENT_BODY TRUE
J 0
(9880 1205);
DISPLAY 0.872340 (9880 1205);
PAINT PEACH (9880 1205);
DISPLAY INVISIBLE (9880 1205);
FORCEPROP 2 LAST PATH I162
J 0
(10100 1375);
DISPLAY 1.021277 (10100 1375);
DISPLAY INVISIBLE (10100 1375);
FORCEPROP 2 LAST CDS_LIB standard
J 0
(9925 1300);
DISPLAY INVISIBLE (9925 1300);
FORCEADD OFFPAGE..1
R 2
(9200 5150);
FORCEPROP 2 LAST $XR0 227 
J 0
(9386 5150);
DISPLAY 0.638298 (9386 5150);
PAINT MONO (9386 5150);
FORCEPROP 1 LAST COMMENT_BODY TRUE
J 2
(9075 5050);
DISPLAY 0.872340 (9075 5050);
PAINT GREEN (9075 5050);
DISPLAY INVISIBLE (9075 5050);
FORCEPROP 1 LAST OFFPAGE TRUE
J 2
(8875 5025);
DISPLAY 0.872340 (8875 5025);
PAINT GREEN (8875 5025);
DISPLAY INVISIBLE (8875 5025);
FORCEPROP 2 LAST PATH I163
J 0
(9375 5225);
DISPLAY 1.021277 (9375 5225);
DISPLAY INVISIBLE (9375 5225);
FORCEPROP 2 LAST CDS_LIB standard
J 0
(9200 5150);
DISPLAY INVISIBLE (9200 5150);
FORCEADD Q_RES..1
(8650 975);
FORCEPROP 1 LAST PART_NUMBER CS00002JB13
J 0
(8600 1025);
DISPLAY 0.404255 (8600 1025);
DISPLAY INVISIBLE (8600 1025);
FORCEPROP 1 LAST MATERIAL CHIP
J 0
(8900 975);
DISPLAY 0.510638 (8900 975);
FORCEPROP 1 LAST TOLERANCE 5%
J 0
(8825 975);
DISPLAY 0.510638 (8825 975);
FORCEPROP 1 LAST VALUE 0
J 2
(8800 975);
DISPLAY 0.510638 (8800 975);
FORCEPROP 1 LAST $LOCATION R4802
J 0
(8425 975);
DISPLAY 0.638298 (8425 975);
FORCEPROP 1 LASTPIN (8550 975) $PN 1
J 0
(8562 987);
DISPLAY 0.787234 (8562 987);
PAINT MONO (8562 987);
FORCEPROP 1 LASTPIN (8750 975) $PN 2
J 0
(8712 987);
DISPLAY 0.787234 (8712 987);
PAINT MONO (8712 987);
FORCEPROP 1 LAST WATTAGE 1/16W
J 2
(8825 1050);
DISPLAY 0.404255 (8825 1050);
DISPLAY INVISIBLE (8825 1050);
FORCEPROP 1 LAST PACK_TYPE 0402LF
J 0
(8900 975);
DISPLAY 0.510638 (8900 975);
DISPLAY INVISIBLE (8900 975);
FORCEPROP 1 LAST PATH I164
J 0
(8600 1125);
DISPLAY 0.978723 (8600 1125);
PAINT WHITE (8600 1125);
DISPLAY INVISIBLE (8600 1125);
FORCEPROP 2 LAST CDS_LIB pure_quanta
J 0
(8650 975);
DISPLAY INVISIBLE (8650 975);
FORCEPROP 0 LAST CDS_LOCATION R4802
J 0
(8600 1075);
DISPLAY 1.021277 (8600 1075);
DISPLAY INVISIBLE (8600 1075);
FORCEPROP 0 LAST $SEC 1
J 0
(8600 1075);
DISPLAY 0.680851 (8600 1075);
PAINT MONO (8600 1075);
DISPLAY INVISIBLE (8600 1075);
FORCEPROP 0 LAST CDS_SEC 1
J 0
(8600 1075);
DISPLAY 1.021277 (8600 1075);
DISPLAY INVISIBLE (8600 1075);
FORCEADD OFFPAGE..1
(7425 975);
FORCEPROP 2 LAST $XR0 144 
J 0
(7173 975);
DISPLAY 0.638298 (7173 975);
PAINT MONO (7173 975);
FORCEPROP 2 LAST CDS_LIB standard
J 0
(7425 975);
DISPLAY INVISIBLE (7425 975);
FORCEPROP 2 LAST PATH I165
J 0
(7475 1050);
DISPLAY 1.021277 (7475 1050);
DISPLAY INVISIBLE (7475 1050);
FORCEPROP 1 LAST OFFPAGE TRUE
J 0
(7750 850);
DISPLAY 0.872340 (7750 850);
DISPLAY INVISIBLE (7750 850);
FORCEPROP 1 LAST COMMENT_BODY TRUE
J 0
(7550 875);
DISPLAY 1.170213 (7550 875);
PAINT GREEN (7550 875);
DISPLAY INVISIBLE (7550 875);
FORCEADD OFFPAGE..2
(9950 975);
FORCEPROP 2 LAST $XR0 227 
J 0
(10139 975);
DISPLAY 0.638298 (10139 975);
PAINT MONO (10139 975);
FORCEPROP 2 LAST CDS_LIB standard
J 0
(9950 975);
DISPLAY INVISIBLE (9950 975);
FORCEPROP 2 LAST PATH I166
J 0
(10125 1050);
DISPLAY 1.021277 (10125 1050);
DISPLAY INVISIBLE (10125 1050);
FORCEPROP 1 LAST OFFPAGE TRUE
J 0
(10275 850);
DISPLAY 0.872340 (10275 850);
PAINT GREEN (10275 850);
DISPLAY INVISIBLE (10275 850);
FORCEPROP 1 LAST COMMENT_BODY TRUE
J 0
(9905 880);
DISPLAY 0.872340 (9905 880);
PAINT PEACH (9905 880);
DISPLAY INVISIBLE (9905 880);
FORCEADD OFFPAGE..1
R 2
(9200 5050);
FORCEPROP 2 LAST $XR0 227 
J 0
(9386 5050);
DISPLAY 0.638298 (9386 5050);
PAINT MONO (9386 5050);
FORCEPROP 1 LAST COMMENT_BODY TRUE
J 2
(9075 4950);
DISPLAY 0.872340 (9075 4950);
PAINT GREEN (9075 4950);
DISPLAY INVISIBLE (9075 4950);
FORCEPROP 1 LAST OFFPAGE TRUE
J 2
(8875 4925);
DISPLAY 0.872340 (8875 4925);
PAINT GREEN (8875 4925);
DISPLAY INVISIBLE (8875 4925);
FORCEPROP 2 LAST PATH I167
J 0
(9375 5125);
DISPLAY 1.021277 (9375 5125);
DISPLAY INVISIBLE (9375 5125);
FORCEPROP 2 LAST CDS_LIB standard
J 0
(9200 5050);
DISPLAY INVISIBLE (9200 5050);
FORCEADD OFFPAGE..2
(9950 3750);
FORCEPROP 2 LAST $XR0 151 
J 0
(10139 3750);
DISPLAY 0.638298 (10139 3750);
PAINT MONO (10139 3750);
FORCEPROP 2 LAST PATH I33
J 0
(10150 3800);
DISPLAY 1.021277 (10150 3800);
DISPLAY INVISIBLE (10150 3800);
FORCEPROP 1 LAST COMMENT_BODY TRUE
J 0
(9905 3655);
DISPLAY 0.872340 (9905 3655);
PAINT PEACH (9905 3655);
DISPLAY INVISIBLE (9905 3655);
FORCEPROP 1 LAST OFFPAGE TRUE
J 0
(10275 3625);
DISPLAY 0.872340 (10275 3625);
PAINT GREEN (10275 3625);
DISPLAY INVISIBLE (10275 3625);
FORCEPROP 2 LAST CDS_LIB standard
J 0
(9950 3750);
PAINT MONO (9950 3750);
DISPLAY INVISIBLE (9950 3750);
FORCEADD Q_RES..1
(8675 3750);
FORCEPROP 1 LAST PART_NUMBER CS00002JB13
J 0
(8625 3800);
DISPLAY 0.404255 (8625 3800);
DISPLAY INVISIBLE (8625 3800);
FORCEPROP 1 LAST MATERIAL CHIP
J 0
(8925 3750);
DISPLAY 0.510638 (8925 3750);
FORCEPROP 1 LAST TOLERANCE 5%
J 0
(8850 3750);
DISPLAY 0.510638 (8850 3750);
FORCEPROP 1 LAST VALUE 0
J 2
(8825 3750);
DISPLAY 0.510638 (8825 3750);
FORCEPROP 1 LAST $LOCATION R2848
J 0
(8475 3750);
DISPLAY 0.510638 (8475 3750);
FORCEPROP 1 LASTPIN (8575 3750) $PN 1
J 0
(8587 3762);
DISPLAY 0.787234 (8587 3762);
PAINT MONO (8587 3762);
FORCEPROP 1 LASTPIN (8775 3750) $PN 2
J 0
(8737 3762);
DISPLAY 0.787234 (8737 3762);
PAINT MONO (8737 3762);
FORCEPROP 1 LAST PATH I34
J 0
(8625 3900);
DISPLAY 0.978723 (8625 3900);
PAINT WHITE (8625 3900);
DISPLAY INVISIBLE (8625 3900);
FORCEPROP 1 LAST WATTAGE 1/16W
J 2
(8850 3825);
DISPLAY 0.404255 (8850 3825);
DISPLAY INVISIBLE (8850 3825);
FORCEPROP 1 LAST PACK_TYPE 0402LF
J 0
(8925 3750);
DISPLAY 0.510638 (8925 3750);
DISPLAY INVISIBLE (8925 3750);
FORCEPROP 2 LAST CDS_LIB pure_quanta
J 0
(8675 3750);
DISPLAY INVISIBLE (8675 3750);
FORCEPROP 0 LAST CDS_LOCATION R2848
J 0
(8925 3775);
DISPLAY 1.021277 (8925 3775);
DISPLAY INVISIBLE (8925 3775);
FORCEPROP 0 LAST $SEC 1
J 0
(8925 3775);
DISPLAY 0.680851 (8925 3775);
PAINT MONO (8925 3775);
DISPLAY INVISIBLE (8925 3775);
FORCEPROP 0 LAST CDS_SEC 1
J 0
(8925 3775);
DISPLAY 1.021277 (8925 3775);
DISPLAY INVISIBLE (8925 3775);
FORCEADD OFFPAGE..1
(7450 3750);
FORCEPROP 2 LAST $XR0 227 
J 0
(7198 3750);
DISPLAY 0.638298 (7198 3750);
PAINT MONO (7198 3750);
FORCEPROP 2 LAST PATH I35
J 0
(7150 3800);
DISPLAY 1.021277 (7150 3800);
DISPLAY INVISIBLE (7150 3800);
FORCEPROP 1 LAST OFFPAGE TRUE
J 0
(7775 3625);
DISPLAY 0.872340 (7775 3625);
DISPLAY INVISIBLE (7775 3625);
FORCEPROP 1 LAST COMMENT_BODY TRUE
J 0
(7575 3650);
DISPLAY 1.170213 (7575 3650);
PAINT GREEN (7575 3650);
DISPLAY INVISIBLE (7575 3650);
FORCEPROP 2 LAST CDS_LIB standard
J 0
(7450 3750);
DISPLAY INVISIBLE (7450 3750);
FORCEADD PCA9539RPW..1
(7875 5200);
FORCEPROP 1 LAST PART_NUMBER AL009539K07
J 0
(7628 5936);
DISPLAY 0.723404 (7628 5936);
PAINT GREEN (7628 5936);
DISPLAY INVISIBLE (7628 5936);
FORCEPROP 2 LAST PART_TYPE SMLF
J 0
(7650 6175);
DISPLAY 1.021277 (7650 6175);
FORCEPROP 2 LAST VALUE PCA9539RPW
J 0
(7650 6125);
DISPLAY 1.021277 (7650 6125);
FORCEPROP 1 LAST MATERIAL IC
J 0
(7628 5809);
DISPLAY 0.723404 (7628 5809);
PAINT GREEN (7628 5809);
FORCEPROP 1 LAST LOCATION U181
J 0
(7628 6083);
DISPLAY 0.723404 (7628 6083);
PAINT GREEN (7628 6083);
FORCEPROP 2 LASTPIN (8275 4950) $PN 21
J 0
(8285 4960);
DISPLAY 0.680851 (8285 4960);
PAINT MONO (8285 4960);
FORCEPROP 2 LASTPIN (7475 5650) $PN 2
J 2
(7465 5660);
DISPLAY 0.680851 (7465 5660);
PAINT MONO (7465 5660);
FORCEPROP 2 LASTPIN (7475 5750) $PN 1
J 2
(7465 5760);
DISPLAY 0.680851 (7465 5760);
PAINT MONO (7465 5760);
FORCEPROP 2 LASTPIN (7475 5450) $PN 4
J 2
(7465 5460);
DISPLAY 0.680851 (7465 5460);
PAINT MONO (7465 5460);
FORCEPROP 2 LASTPIN (7475 5350) $PN 5
J 2
(7465 5360);
DISPLAY 0.680851 (7465 5360);
PAINT MONO (7465 5360);
FORCEPROP 2 LASTPIN (7475 5250) $PN 6
J 2
(7465 5260);
DISPLAY 0.680851 (7465 5260);
PAINT MONO (7465 5260);
FORCEPROP 2 LASTPIN (7475 5150) $PN 7
J 2
(7465 5160);
DISPLAY 0.680851 (7465 5160);
PAINT MONO (7465 5160);
FORCEPROP 2 LASTPIN (7475 5050) $PN 8
J 2
(7465 5060);
DISPLAY 0.680851 (7465 5060);
PAINT MONO (7465 5060);
FORCEPROP 2 LASTPIN (7475 4950) $PN 9
J 2
(7465 4960);
DISPLAY 0.680851 (7465 4960);
PAINT MONO (7465 4960);
FORCEPROP 2 LASTPIN (7475 4850) $PN 10
J 2
(7465 4860);
DISPLAY 0.680851 (7465 4860);
PAINT MONO (7465 4860);
FORCEPROP 2 LASTPIN (7475 4750) $PN 11
J 2
(7465 4760);
DISPLAY 0.680851 (7465 4760);
PAINT MONO (7465 4760);
FORCEPROP 2 LASTPIN (8275 5750) $PN 13
J 0
(8285 5760);
DISPLAY 0.680851 (8285 5760);
PAINT MONO (8285 5760);
FORCEPROP 2 LASTPIN (8275 5650) $PN 14
J 0
(8285 5660);
DISPLAY 0.680851 (8285 5660);
PAINT MONO (8285 5660);
FORCEPROP 2 LASTPIN (8275 5550) $PN 15
J 0
(8285 5560);
DISPLAY 0.680851 (8285 5560);
PAINT MONO (8285 5560);
FORCEPROP 2 LASTPIN (8275 5450) $PN 16
J 0
(8285 5460);
DISPLAY 0.680851 (8285 5460);
PAINT MONO (8285 5460);
FORCEPROP 2 LASTPIN (8275 5350) $PN 17
J 0
(8285 5360);
DISPLAY 0.680851 (8285 5360);
PAINT MONO (8285 5360);
FORCEPROP 2 LASTPIN (8275 5250) $PN 18
J 0
(8285 5260);
DISPLAY 0.680851 (8285 5260);
PAINT MONO (8285 5260);
FORCEPROP 2 LASTPIN (8275 5150) $PN 19
J 0
(8285 5160);
DISPLAY 0.680851 (8285 5160);
PAINT MONO (8285 5160);
FORCEPROP 2 LASTPIN (8275 5050) $PN 20
J 0
(8285 5060);
DISPLAY 0.680851 (8285 5060);
PAINT MONO (8285 5060);
FORCEPROP 2 LASTPIN (7475 5550) $PN 3
J 2
(7465 5560);
DISPLAY 0.680851 (7465 5560);
PAINT MONO (7465 5560);
FORCEPROP 2 LASTPIN (8275 4850) $PN 22
J 0
(8285 4860);
DISPLAY 0.680851 (8285 4860);
PAINT MONO (8285 4860);
FORCEPROP 2 LASTPIN (8275 4750) $PN 23
J 0
(8285 4760);
DISPLAY 0.680851 (8285 4760);
PAINT MONO (8285 4760);
FORCEPROP 2 LASTPIN (8275 4650) $PN 24
J 0
(8285 4660);
DISPLAY 0.680851 (8285 4660);
PAINT MONO (8285 4660);
FORCEPROP 2 LASTPIN (7475 4650) $PN 12
J 2
(7465 4660);
DISPLAY 0.680851 (7465 4660);
PAINT MONO (7465 4660);
FORCEPROP 2 LAST SEC_TYPE 
J 0
(7650 6225);
DISPLAY 1.021277 (7650 6225);
DISPLAY INVISIBLE (7650 6225);
FORCEPROP 2 LAST CDS_LIB pure_quanta
J 0
(7875 5200);
DISPLAY INVISIBLE (7875 5200);
FORCEPROP 1 LAST PATH I66
J 0
(7875 5200);
DISPLAY 0.723404 (7875 5200);
PAINT GREEN (7875 5200);
DISPLAY INVISIBLE (7875 5200);
FORCEPROP 1 LAST NEEDS_NO_SIZE TRUE
J 0
(7875 5200);
DISPLAY 0.723404 (7875 5200);
PAINT GREEN (7875 5200);
DISPLAY INVISIBLE (7875 5200);
FORCEPROP 1 LAST CDS_LMAN_SYM_OUTLINE -250,600,250,-600
J 0
(7875 5200);
DISPLAY 0.468085 (7875 5200);
PAINT GREEN (7875 5200);
DISPLAY INVISIBLE (7875 5200);
FORCEPROP 2 LAST SEC 1
J 0
(7650 6225);
DISPLAY 0.680851 (7650 6225);
PAINT MONO (7650 6225);
DISPLAY INVISIBLE (7650 6225);
FORCEADD UNIVERSAL_POWER..1
(5100 3775);
FORCEPROP 3 LASTPIN (5100 3725) SIG_NAME P3V3_AUX\g
J 0
(5110 3735);
DISPLAY 0.659574 (5110 3735);
PAINT MONO (5110 3735);
DISPLAY INVISIBLE (5110 3735);
FORCEPROP 1 LAST HDL_POWER P3V3_AUX
J 1
(5100 3825);
DISPLAY 0.872340 (5100 3825);
PAINT GREEN (5100 3825);
FORCEPROP 2 LAST CDS_LIB logical_power
J 0
(5100 3775);
PAINT MONO (5100 3775);
DISPLAY INVISIBLE (5100 3775);
FORCEPROP 1 LAST PATH I73
J 0
(5150 3800);
DISPLAY 0.872340 (5150 3800);
PAINT AQUA (5150 3800);
DISPLAY INVISIBLE (5150 3800);
FORCEADD Q_RES..2
(5350 3375);
FORCEPROP 1 LAST PART_NUMBER CS21002FB06
J 0
(5390 3200);
DISPLAY 0.638298 (5390 3200);
DISPLAY INVISIBLE (5390 3200);
FORCEPROP 1 LAST WATTAGE 1/16W
J 0
(5390 3350);
DISPLAY 0.638298 (5390 3350);
FORCEPROP 1 LAST VALUE 1K
J 0
(5395 3450);
DISPLAY 0.638298 (5395 3450);
FORCEPROP 1 LAST PACK_TYPE 0402LF
J 0
(5390 3250);
DISPLAY 0.638298 (5390 3250);
FORCEPROP 1 LAST TOLERANCE 1%
J 0
(5395 3400);
DISPLAY 0.638298 (5395 3400);
FORCEPROP 1 LAST MATERIAL EMPTY
J 0
(5390 3300);
DISPLAY 0.638298 (5390 3300);
PAINT RED (5390 3300);
FORCEPROP 1 LAST $LOCATION R2695
J 0
(5395 3500);
DISPLAY 0.638298 (5395 3500);
FORCEPROP 1 LASTPIN (5350 3475) $PN 1
J 0
(5355 3437);
DISPLAY 0.787234 (5355 3437);
PAINT MONO (5355 3437);
FORCEPROP 1 LASTPIN (5350 3275) $PN 2
J 0
(5355 3285);
DISPLAY 0.787234 (5355 3285);
PAINT MONO (5355 3285);
FORCEPROP 2 LAST CDS_LIB pure_quanta
J 0
(5350 3375);
DISPLAY INVISIBLE (5350 3375);
FORCEPROP 1 LAST PATH I74
J 0
(5400 3550);
DISPLAY 0.978723 (5400 3550);
PAINT WHITE (5400 3550);
DISPLAY INVISIBLE (5400 3550);
FORCEPROP 0 LAST CDS_LOCATION R2695
J 0
(5400 3550);
DISPLAY 1.021277 (5400 3550);
DISPLAY INVISIBLE (5400 3550);
FORCEPROP 0 LAST $SEC 1
J 0
(5400 3550);
DISPLAY 0.680851 (5400 3550);
PAINT MONO (5400 3550);
DISPLAY INVISIBLE (5400 3550);
FORCEPROP 0 LAST CDS_SEC 1
J 0
(5400 3550);
DISPLAY 1.021277 (5400 3550);
DISPLAY INVISIBLE (5400 3550);
FORCEADD Q_RES..2
(5350 2775);
FORCEPROP 1 LAST PART_NUMBER CS21002FB06
J 0
(5390 2600);
DISPLAY 0.638298 (5390 2600);
DISPLAY INVISIBLE (5390 2600);
FORCEPROP 1 LAST MATERIAL CHIP
J 0
(5390 2700);
DISPLAY 0.638298 (5390 2700);
FORCEPROP 1 LAST PACK_TYPE 0402LF
J 0
(5390 2650);
DISPLAY 0.638298 (5390 2650);
FORCEPROP 1 LAST WATTAGE 1/16W
J 0
(5390 2750);
DISPLAY 0.638298 (5390 2750);
FORCEPROP 1 LAST VALUE 1K
J 0
(5395 2850);
DISPLAY 0.638298 (5395 2850);
FORCEPROP 1 LAST TOLERANCE 1%
J 0
(5395 2800);
DISPLAY 0.638298 (5395 2800);
FORCEPROP 1 LAST $LOCATION R2696
J 0
(5395 2900);
DISPLAY 0.638298 (5395 2900);
FORCEPROP 1 LASTPIN (5350 2875) $PN 1
J 0
(5355 2837);
DISPLAY 0.787234 (5355 2837);
PAINT MONO (5355 2837);
FORCEPROP 1 LASTPIN (5350 2675) $PN 2
J 0
(5355 2685);
DISPLAY 0.787234 (5355 2685);
PAINT MONO (5355 2685);
FORCEPROP 2 LAST CDS_LIB pure_quanta
J 0
(5350 2775);
DISPLAY INVISIBLE (5350 2775);
FORCEPROP 1 LAST PATH I75
J 0
(5400 2950);
DISPLAY 0.978723 (5400 2950);
PAINT WHITE (5400 2950);
DISPLAY INVISIBLE (5400 2950);
FORCEPROP 0 LAST CDS_LOCATION R2696
J 0
(5400 2950);
DISPLAY 1.021277 (5400 2950);
DISPLAY INVISIBLE (5400 2950);
FORCEPROP 0 LAST $SEC 1
J 0
(5400 2950);
DISPLAY 0.680851 (5400 2950);
PAINT MONO (5400 2950);
DISPLAY INVISIBLE (5400 2950);
FORCEPROP 0 LAST CDS_SEC 1
J 0
(5400 2950);
DISPLAY 1.021277 (5400 2950);
DISPLAY INVISIBLE (5400 2950);
FORCEADD Q_RES..2
(5100 3375);
FORCEPROP 1 LAST PART_NUMBER CS21002FB06
J 0
(5140 3200);
DISPLAY 0.638298 (5140 3200);
DISPLAY INVISIBLE (5140 3200);
FORCEPROP 1 LAST TOLERANCE 1%
J 0
(5145 3400);
DISPLAY 0.638298 (5145 3400);
FORCEPROP 1 LAST WATTAGE 1/16W
J 0
(5140 3350);
DISPLAY 0.638298 (5140 3350);
FORCEPROP 1 LAST VALUE 1K
J 0
(5145 3450);
DISPLAY 0.638298 (5145 3450);
FORCEPROP 1 LAST MATERIAL EMPTY
J 0
(5140 3300);
DISPLAY 0.638298 (5140 3300);
PAINT RED (5140 3300);
FORCEPROP 1 LAST PACK_TYPE 0402LF
J 0
(5140 3250);
DISPLAY 0.638298 (5140 3250);
FORCEPROP 1 LAST $LOCATION R2693
J 0
(5145 3500);
DISPLAY 0.638298 (5145 3500);
FORCEPROP 1 LASTPIN (5100 3475) $PN 1
J 0
(5105 3437);
DISPLAY 0.787234 (5105 3437);
PAINT MONO (5105 3437);
FORCEPROP 1 LASTPIN (5100 3275) $PN 2
J 0
(5105 3285);
DISPLAY 0.787234 (5105 3285);
PAINT MONO (5105 3285);
FORCEPROP 2 LAST CDS_LIB pure_quanta
J 0
(5100 3375);
DISPLAY INVISIBLE (5100 3375);
FORCEPROP 1 LAST PATH I76
J 0
(5150 3550);
DISPLAY 0.978723 (5150 3550);
PAINT WHITE (5150 3550);
DISPLAY INVISIBLE (5150 3550);
FORCEPROP 0 LAST CDS_LOCATION R2693
J 0
(5150 3550);
DISPLAY 1.021277 (5150 3550);
DISPLAY INVISIBLE (5150 3550);
FORCEPROP 0 LAST $SEC 1
J 0
(5150 3550);
DISPLAY 0.680851 (5150 3550);
PAINT MONO (5150 3550);
DISPLAY INVISIBLE (5150 3550);
FORCEPROP 0 LAST CDS_SEC 1
J 0
(5150 3550);
DISPLAY 1.021277 (5150 3550);
DISPLAY INVISIBLE (5150 3550);
FORCEADD Q_RES..2
(5100 2775);
FORCEPROP 1 LAST PART_NUMBER CS21002FB06
J 0
(5140 2600);
DISPLAY 0.638298 (5140 2600);
DISPLAY INVISIBLE (5140 2600);
FORCEPROP 1 LAST MATERIAL CHIP
J 0
(5140 2700);
DISPLAY 0.638298 (5140 2700);
FORCEPROP 1 LAST PACK_TYPE 0402LF
J 0
(5140 2650);
DISPLAY 0.638298 (5140 2650);
FORCEPROP 1 LAST VALUE 1K
J 0
(5145 2850);
DISPLAY 0.638298 (5145 2850);
FORCEPROP 1 LAST WATTAGE 1/16W
J 0
(5140 2750);
DISPLAY 0.638298 (5140 2750);
FORCEPROP 1 LAST TOLERANCE 1%
J 0
(5145 2800);
DISPLAY 0.638298 (5145 2800);
FORCEPROP 1 LAST $LOCATION R2694
J 0
(5145 2900);
DISPLAY 0.638298 (5145 2900);
FORCEPROP 1 LASTPIN (5100 2875) $PN 1
J 0
(5105 2837);
DISPLAY 0.787234 (5105 2837);
PAINT MONO (5105 2837);
FORCEPROP 1 LASTPIN (5100 2675) $PN 2
J 0
(5105 2685);
DISPLAY 0.787234 (5105 2685);
PAINT MONO (5105 2685);
FORCEPROP 2 LAST CDS_LIB pure_quanta
J 0
(5100 2775);
DISPLAY INVISIBLE (5100 2775);
FORCEPROP 1 LAST PATH I77
J 0
(5150 2950);
DISPLAY 0.978723 (5150 2950);
PAINT WHITE (5150 2950);
DISPLAY INVISIBLE (5150 2950);
FORCEPROP 0 LAST CDS_LOCATION R2694
J 0
(5150 2950);
DISPLAY 1.021277 (5150 2950);
DISPLAY INVISIBLE (5150 2950);
FORCEPROP 0 LAST $SEC 1
J 0
(5150 2950);
DISPLAY 0.680851 (5150 2950);
PAINT MONO (5150 2950);
DISPLAY INVISIBLE (5150 2950);
FORCEPROP 0 LAST CDS_SEC 1
J 0
(5150 2950);
DISPLAY 1.021277 (5150 2950);
DISPLAY INVISIBLE (5150 2950);
FORCEADD UNIVERSAL_GND..1
(5350 2550);
FORCEPROP 3 LASTPIN (5350 2600) SIG_NAME GND\g
J 0
(5360 2610);
DISPLAY 0.659574 (5360 2610);
PAINT MONO (5360 2610);
DISPLAY INVISIBLE (5360 2610);
FORCEPROP 2 LAST CDS_LIB logical_power
J 0
(5350 2550);
PAINT MONO (5350 2550);
DISPLAY INVISIBLE (5350 2550);
FORCEPROP 1 LAST HDL_POWER GND
J 1
(5375 2475);
DISPLAY 0.872340 (5375 2475);
PAINT GREEN (5375 2475);
DISPLAY INVISIBLE (5375 2475);
FORCEPROP 1 LAST PATH I78
J 0
(5425 2550);
DISPLAY 0.872340 (5425 2550);
PAINT AQUA (5425 2550);
DISPLAY INVISIBLE (5425 2550);
FORCEADD UNIVERSAL_GND..1
(5100 2550);
FORCEPROP 3 LASTPIN (5100 2600) SIG_NAME GND\g
J 0
(5110 2610);
DISPLAY 0.659574 (5110 2610);
PAINT MONO (5110 2610);
DISPLAY INVISIBLE (5110 2610);
FORCEPROP 2 LAST CDS_LIB logical_power
J 0
(5100 2550);
PAINT MONO (5100 2550);
DISPLAY INVISIBLE (5100 2550);
FORCEPROP 1 LAST HDL_POWER GND
J 1
(5125 2475);
DISPLAY 0.872340 (5125 2475);
PAINT GREEN (5125 2475);
DISPLAY INVISIBLE (5125 2475);
FORCEPROP 1 LAST PATH I79
J 0
(5175 2550);
DISPLAY 0.872340 (5175 2550);
PAINT AQUA (5175 2550);
DISPLAY INVISIBLE (5175 2550);
FORCEADD OFFPAGE..1
(6300 5650);
FORCEPROP 2 LAST $XR0 227 
J 0
(6048 5650);
DISPLAY 0.638298 (6048 5650);
PAINT MONO (6048 5650);
FORCEPROP 2 LAST CDS_LIB standard
J 2
(6300 5650);
DISPLAY INVISIBLE (6300 5650);
FORCEPROP 1 LAST COMMENT_BODY TRUE
J 0
(6425 5550);
DISPLAY 0.872340 (6425 5550);
PAINT GREEN (6425 5550);
DISPLAY INVISIBLE (6425 5550);
FORCEPROP 1 LAST OFFPAGE TRUE
J 0
(6625 5525);
DISPLAY 0.872340 (6625 5525);
PAINT GREEN (6625 5525);
DISPLAY INVISIBLE (6625 5525);
FORCEPROP 2 LAST PATH I80
J 0
(6125 5700);
DISPLAY 1.021277 (6125 5700);
DISPLAY INVISIBLE (6125 5700);
FORCEADD OFFPAGE..2
(6225 3025);
FORCEPROP 2 LAST $XR0 227 
J 0
(6414 3025);
DISPLAY 0.638298 (6414 3025);
PAINT MONO (6414 3025);
FORCEPROP 2 LAST CDS_LIB standard
J 0
(6225 3025);
DISPLAY INVISIBLE (6225 3025);
FORCEPROP 1 LAST COMMENT_BODY TRUE
J 0
(6180 2930);
DISPLAY 0.872340 (6180 2930);
PAINT GREEN (6180 2930);
DISPLAY INVISIBLE (6180 2930);
FORCEPROP 1 LAST OFFPAGE TRUE
J 0
(6550 2900);
DISPLAY 0.872340 (6550 2900);
DISPLAY INVISIBLE (6550 2900);
FORCEPROP 2 LAST PATH I81
J 0
(6550 3075);
DISPLAY 1.021277 (6550 3075);
DISPLAY INVISIBLE (6550 3075);
FORCEADD OFFPAGE..2
(6225 3125);
FORCEPROP 2 LAST $XR0 227 
J 0
(6414 3125);
DISPLAY 0.638298 (6414 3125);
PAINT MONO (6414 3125);
FORCEPROP 2 LAST PATH I82
J 0
(6425 3175);
DISPLAY 1.021277 (6425 3175);
DISPLAY INVISIBLE (6425 3175);
FORCEPROP 2 LAST CDS_LIB standard
J 0
(6225 3125);
DISPLAY INVISIBLE (6225 3125);
FORCEPROP 1 LAST OFFPAGE TRUE
J 0
(6550 3000);
DISPLAY 0.872340 (6550 3000);
DISPLAY INVISIBLE (6550 3000);
FORCEPROP 1 LAST COMMENT_BODY TRUE
J 0
(6180 3030);
DISPLAY 0.872340 (6180 3030);
PAINT GREEN (6180 3030);
DISPLAY INVISIBLE (6180 3030);
FORCEADD OFFPAGE..1
R 2
(9175 4950);
FORCEPROP 2 LAST $XR0 227 
J 0
(9361 4950);
DISPLAY 0.638298 (9361 4950);
PAINT MONO (9361 4950);
FORCEPROP 1 LAST OFFPAGE TRUE
J 2
(8850 4825);
DISPLAY 0.872340 (8850 4825);
PAINT GREEN (8850 4825);
DISPLAY INVISIBLE (8850 4825);
FORCEPROP 1 LAST COMMENT_BODY TRUE
J 2
(9050 4850);
DISPLAY 0.872340 (9050 4850);
PAINT GREEN (9050 4850);
DISPLAY INVISIBLE (9050 4850);
FORCEPROP 2 LAST PATH I83
J 2
(9125 5025);
DISPLAY 1.021277 (9125 5025);
DISPLAY INVISIBLE (9125 5025);
FORCEPROP 2 LAST CDS_LIB standard
J 2
(9175 4950);
DISPLAY INVISIBLE (9175 4950);
FORCEADD OFFPAGE..1
R 2
(9175 4850);
FORCEPROP 2 LAST $XR0 227 
J 0
(9361 4850);
DISPLAY 0.638298 (9361 4850);
PAINT MONO (9361 4850);
FORCEPROP 2 LAST CDS_LIB standard
J 2
(9175 4850);
PAINT MONO (9175 4850);
DISPLAY INVISIBLE (9175 4850);
FORCEPROP 1 LAST COMMENT_BODY TRUE
J 2
(9050 4750);
DISPLAY 0.872340 (9050 4750);
PAINT GREEN (9050 4750);
DISPLAY INVISIBLE (9050 4750);
FORCEPROP 1 LAST OFFPAGE TRUE
J 2
(8850 4725);
DISPLAY 0.872340 (8850 4725);
PAINT GREEN (8850 4725);
DISPLAY INVISIBLE (8850 4725);
FORCEPROP 2 LAST PATH I84
J 0
(9475 4900);
DISPLAY 1.021277 (9475 4900);
DISPLAY INVISIBLE (9475 4900);
FORCEADD OFFPAGE..3
(9175 4750);
FORCEPROP 2 LAST $XR0 227 
J 0
(9389 4750);
DISPLAY 0.638298 (9389 4750);
PAINT MONO (9389 4750);
FORCEPROP 2 LAST PATH I85
J 0
(9475 4800);
DISPLAY 1.021277 (9475 4800);
DISPLAY INVISIBLE (9475 4800);
FORCEPROP 1 LAST OFFPAGE TRUE
J 0
(9500 4625);
DISPLAY 0.872340 (9500 4625);
DISPLAY INVISIBLE (9500 4625);
FORCEPROP 1 LAST COMMENT_BODY TRUE
J 0
(9125 4650);
DISPLAY 0.872340 (9125 4650);
PAINT GREEN (9125 4650);
DISPLAY INVISIBLE (9125 4650);
FORCEPROP 2 LAST CDS_LIB standard
J 2
(9175 4750);
PAINT MONO (9175 4750);
DISPLAY INVISIBLE (9175 4750);
FORCEADD UNIVERSAL_GND..1
(7325 4425);
FORCEPROP 3 LASTPIN (7325 4475) SIG_NAME GND\g
J 0
(7335 4485);
DISPLAY 0.659574 (7335 4485);
PAINT MONO (7335 4485);
DISPLAY INVISIBLE (7335 4485);
FORCEPROP 1 LAST PATH I86
J 0
(7400 4425);
DISPLAY 0.872340 (7400 4425);
PAINT AQUA (7400 4425);
DISPLAY INVISIBLE (7400 4425);
FORCEPROP 2 LAST CDS_LIB logical_power
J 0
(7325 4425);
PAINT MONO (7325 4425);
DISPLAY INVISIBLE (7325 4425);
FORCEPROP 1 LAST HDL_POWER GND
J 1
(7350 4350);
DISPLAY 0.872340 (7350 4350);
PAINT GREEN (7350 4350);
DISPLAY INVISIBLE (7350 4350);
FORCEADD Q_CAP..1
R 2
(9000 4150);
FORCEPROP 1 LAST PART_NUMBER CH4104K1B00
J 2
(8950 4000);
DISPLAY 0.510638 (8950 4000);
DISPLAY INVISIBLE (8950 4000);
FORCEPROP 1 LAST VALUE 0.1UF
J 2
(8950 4200);
DISPLAY 0.510638 (8950 4200);
FORCEPROP 1 LAST PACK_TYPE 0402
J 2
(8950 3950);
DISPLAY 0.510638 (8950 3950);
FORCEPROP 1 LAST MATERIAL X7R
J 2
(8950 4050);
DISPLAY 0.510638 (8950 4050);
FORCEPROP 1 LAST TOLERANCE 10%
J 2
(8950 4100);
DISPLAY 0.510638 (8950 4100);
FORCEPROP 1 LAST VOLTAGE 25V
J 2
(8950 4150);
DISPLAY 0.510638 (8950 4150);
FORCEPROP 1 LAST $LOCATION C1713
J 2
(8950 4250);
DISPLAY 0.787234 (8950 4250);
FORCEPROP 1 LASTPIN (9000 4250) $PN 1
J 2
(8990 4230);
DISPLAY 0.787234 (8990 4230);
PAINT MONO (8990 4230);
FORCEPROP 1 LASTPIN (9000 4050) $PN 2
J 2
(8990 4030);
DISPLAY 0.787234 (8990 4030);
PAINT MONO (8990 4030);
FORCEPROP 1 LAST PATH I87
J 2
(8950 4300);
DISPLAY 0.978723 (8950 4300);
PAINT WHITE (8950 4300);
DISPLAY INVISIBLE (8950 4300);
FORCEPROP 2 LAST CDS_LIB pure_quanta
J 0
(9000 4150);
DISPLAY INVISIBLE (9000 4150);
FORCEPROP 0 LAST CDS_LOCATION C1713
J 0
(8950 4300);
DISPLAY 1.021277 (8950 4300);
DISPLAY INVISIBLE (8950 4300);
FORCEPROP 0 LAST $SEC 1
J 0
(8950 4300);
DISPLAY 0.680851 (8950 4300);
PAINT MONO (8950 4300);
DISPLAY INVISIBLE (8950 4300);
FORCEPROP 0 LAST CDS_SEC 1
J 0
(8950 4300);
DISPLAY 1.021277 (8950 4300);
DISPLAY INVISIBLE (8950 4300);
FORCEADD UNIVERSAL_POWER..1
(9000 4425);
FORCEPROP 3 LASTPIN (9000 4375) SIG_NAME P3V3_AUX\g
J 0
(9010 4385);
DISPLAY 0.659574 (9010 4385);
PAINT MONO (9010 4385);
DISPLAY INVISIBLE (9010 4385);
FORCEPROP 1 LAST HDL_POWER P3V3_AUX
J 1
(9000 4475);
DISPLAY 0.872340 (9000 4475);
PAINT GREEN (9000 4475);
FORCEPROP 1 LAST PATH I88
J 0
(9050 4450);
DISPLAY 0.872340 (9050 4450);
PAINT AQUA (9050 4450);
DISPLAY INVISIBLE (9050 4450);
FORCEPROP 2 LAST CDS_LIB logical_power
J 0
(9000 4425);
PAINT MONO (9000 4425);
DISPLAY INVISIBLE (9000 4425);
FORCEADD UNIVERSAL_GND..1
(9000 3925);
FORCEPROP 3 LASTPIN (9000 3975) SIG_NAME GND\g
J 0
(9010 3985);
DISPLAY 0.659574 (9010 3985);
PAINT MONO (9010 3985);
DISPLAY INVISIBLE (9010 3985);
FORCEPROP 1 LAST PATH I89
J 0
(9075 3925);
DISPLAY 0.872340 (9075 3925);
PAINT AQUA (9075 3925);
DISPLAY INVISIBLE (9075 3925);
FORCEPROP 1 LAST HDL_POWER GND
J 1
(9025 3850);
DISPLAY 0.872340 (9025 3850);
PAINT GREEN (9025 3850);
DISPLAY INVISIBLE (9025 3850);
FORCEPROP 2 LAST CDS_LIB logical_power
J 0
(9000 3925);
PAINT MONO (9000 3925);
DISPLAY INVISIBLE (9000 3925);
FORCEADD Q_RES..2
(6675 6050);
FORCEPROP 1 LAST PART_NUMBER CS24702JB10
J 0
(6715 5925);
DISPLAY 0.510638 (6715 5925);
DISPLAY INVISIBLE (6715 5925);
FORCEPROP 1 LAST PACK_TYPE 0402LF
J 0
(6715 5875);
DISPLAY 0.510638 (6715 5875);
FORCEPROP 1 LAST TOLERANCE 5%
J 0
(6720 6075);
DISPLAY 0.510638 (6720 6075);
FORCEPROP 1 LAST WATTAGE 1/16W
J 0
(6715 6025);
DISPLAY 0.510638 (6715 6025);
FORCEPROP 1 LAST VALUE 4.7K
J 0
(6720 6125);
DISPLAY 0.510638 (6720 6125);
FORCEPROP 1 LAST MATERIAL EMPTY
J 0
(6715 5975);
DISPLAY 0.510638 (6715 5975);
FORCEPROP 1 LAST $LOCATION R2923
J 0
(6720 6175);
DISPLAY 0.978723 (6720 6175);
FORCEPROP 1 LASTPIN (6675 6150) $PN 1
J 0
(6680 6112);
DISPLAY 0.787234 (6680 6112);
PAINT MONO (6680 6112);
FORCEPROP 1 LASTPIN (6675 5950) $PN 2
J 0
(6680 5960);
DISPLAY 0.787234 (6680 5960);
PAINT MONO (6680 5960);
FORCEPROP 2 LAST CDS_LIB pure_quanta
J 0
(6675 6050);
DISPLAY INVISIBLE (6675 6050);
FORCEPROP 1 LAST PATH I90
J 0
(6725 6225);
DISPLAY 0.978723 (6725 6225);
PAINT WHITE (6725 6225);
DISPLAY INVISIBLE (6725 6225);
FORCEPROP 0 LAST CDS_LOCATION R2923
J 0
(6725 6225);
DISPLAY 1.021277 (6725 6225);
DISPLAY INVISIBLE (6725 6225);
FORCEPROP 0 LAST $SEC 1
J 0
(6725 6225);
DISPLAY 0.680851 (6725 6225);
PAINT MONO (6725 6225);
DISPLAY INVISIBLE (6725 6225);
FORCEPROP 0 LAST CDS_SEC 1
J 0
(6725 6225);
DISPLAY 1.021277 (6725 6225);
DISPLAY INVISIBLE (6725 6225);
FORCEADD UNIVERSAL_POWER..1
(6675 6275);
FORCEPROP 3 LASTPIN (6675 6225) SIG_NAME P3V3_AUX\g
J 0
(6685 6235);
DISPLAY 0.659574 (6685 6235);
PAINT MONO (6685 6235);
DISPLAY INVISIBLE (6685 6235);
FORCEPROP 1 LAST HDL_POWER P3V3_AUX
J 1
(6675 6325);
DISPLAY 0.872340 (6675 6325);
PAINT GREEN (6675 6325);
FORCEPROP 2 LAST CDS_LIB logical_power
J 0
(6675 6275);
DISPLAY INVISIBLE (6675 6275);
FORCEPROP 1 LAST PATH I91
J 0
(6725 6300);
DISPLAY 0.872340 (6725 6300);
PAINT AQUA (6725 6300);
DISPLAY INVISIBLE (6725 6300);
FORCEADD OFFPAGE..1
(5075 5550);
FORCEPROP 2 LAST $XR7 245 
J 0
(3983 5550);
DISPLAY 0.638298 (3983 5550);
PAINT MONO (3983 5550);
FORCEPROP 2 LAST $XR6 236 
J 0
(4103 5550);
DISPLAY 0.638298 (4103 5550);
PAINT MONO (4103 5550);
FORCEPROP 2 LAST $XR5 233 
J 0
(4223 5550);
DISPLAY 0.638298 (4223 5550);
PAINT MONO (4223 5550);
FORCEPROP 2 LAST $XR4 231 
J 0
(4343 5550);
DISPLAY 0.638298 (4343 5550);
PAINT MONO (4343 5550);
FORCEPROP 2 LAST $XR3 191 
J 0
(4463 5550);
DISPLAY 0.638298 (4463 5550);
PAINT MONO (4463 5550);
FORCEPROP 2 LAST $XR2 161 
J 0
(4583 5550);
DISPLAY 0.638298 (4583 5550);
PAINT MONO (4583 5550);
FORCEPROP 2 LAST $XR1 154 
J 0
(4703 5550);
DISPLAY 0.638298 (4703 5550);
PAINT MONO (4703 5550);
FORCEPROP 2 LAST $XR0 215 
J 0
(4823 5550);
DISPLAY 0.638298 (4823 5550);
PAINT MONO (4823 5550);
FORCEPROP 2 LAST PATH I92
J 0
(4800 5600);
DISPLAY 1.021277 (4800 5600);
DISPLAY INVISIBLE (4800 5600);
FORCEPROP 1 LAST COMMENT_BODY TRUE
J 0
(5200 5450);
DISPLAY 0.872340 (5200 5450);
PAINT GREEN (5200 5450);
DISPLAY INVISIBLE (5200 5450);
FORCEPROP 1 LAST OFFPAGE TRUE
J 0
(5400 5425);
DISPLAY 0.872340 (5400 5425);
DISPLAY INVISIBLE (5400 5425);
FORCEPROP 2 LAST CDS_LIB standard
J 0
(5075 5550);
DISPLAY INVISIBLE (5075 5550);
FORCEADD Q_RES..2
R 2
(5900 5925);
FORCEPROP 1 LAST PART_NUMBER CS31002FB08
J 2
(5860 5750);
DISPLAY 0.638298 (5860 5750);
DISPLAY INVISIBLE (5860 5750);
FORCEPROP 1 LAST VALUE 10K
J 2
(5855 6000);
DISPLAY 0.638298 (5855 6000);
FORCEPROP 1 LAST WATTAGE 1/16W
J 2
(5860 5900);
DISPLAY 0.638298 (5860 5900);
FORCEPROP 1 LAST TOLERANCE 1%
J 2
(5855 5950);
DISPLAY 0.638298 (5855 5950);
FORCEPROP 1 LAST PACK_TYPE 0402LF
J 2
(5860 5800);
DISPLAY 0.638298 (5860 5800);
FORCEPROP 1 LAST MATERIAL EMPTY
J 2
(5860 5850);
DISPLAY 0.638298 (5860 5850);
PAINT RED (5860 5850);
FORCEPROP 1 LAST $LOCATION R2921
J 2
(5855 6050);
DISPLAY 0.978723 (5855 6050);
FORCEPROP 1 LASTPIN (5900 6025) $PN 1
J 2
(5895 5987);
DISPLAY 0.787234 (5895 5987);
FORCEPROP 1 LASTPIN (5900 5825) $PN 2
J 2
(5895 5835);
DISPLAY 0.787234 (5895 5835);
FORCEPROP 1 LAST PATH I93
J 2
(5850 6100);
DISPLAY 0.978723 (5850 6100);
PAINT WHITE (5850 6100);
DISPLAY INVISIBLE (5850 6100);
FORCEPROP 2 LAST CDS_LIB pure_quanta
J 2
(5900 5925);
PAINT MONO (5900 5925);
DISPLAY INVISIBLE (5900 5925);
FORCEPROP 2 LAST CDS_LOCATION R2921
J 0
(5850 6150);
DISPLAY 1.021277 (5850 6150);
DISPLAY INVISIBLE (5850 6150);
FORCEPROP 2 LAST $SEC 1
J 0
(5850 6150);
DISPLAY 0.680851 (5850 6150);
PAINT MONO (5850 6150);
DISPLAY INVISIBLE (5850 6150);
FORCEPROP 2 LAST CDS_SEC 1
J 0
(5850 6150);
DISPLAY 1.021277 (5850 6150);
DISPLAY INVISIBLE (5850 6150);
FORCEADD UNIVERSAL_POWER..1
(5900 6200);
FORCEPROP 3 LASTPIN (5900 6150) SIG_NAME P3V3_AUX\g
J 0
(5910 6160);
DISPLAY 0.659574 (5910 6160);
PAINT MONO (5910 6160);
DISPLAY INVISIBLE (5910 6160);
FORCEPROP 1 LAST HDL_POWER P3V3_AUX
J 1
(5900 6250);
DISPLAY 0.872340 (5900 6250);
PAINT GREEN (5900 6250);
FORCEPROP 1 LAST PATH I94
J 0
(5950 6225);
DISPLAY 0.872340 (5950 6225);
PAINT AQUA (5950 6225);
DISPLAY INVISIBLE (5950 6225);
FORCEPROP 2 LAST CDS_LIB logical_power
J 0
(5900 6200);
DISPLAY INVISIBLE (5900 6200);
FORCEADD Q_RES..1
(6250 5550);
FORCEPROP 1 LAST PART_NUMBER CS00002JB13
J 0
(6175 5500);
DISPLAY 0.319149 (6175 5500);
DISPLAY INVISIBLE (6175 5500);
FORCEPROP 1 LAST VALUE 0
J 2
(6400 5550);
DISPLAY 0.510638 (6400 5550);
FORCEPROP 1 LAST MATERIAL CHIP
J 0
(6500 5550);
DISPLAY 0.510638 (6500 5550);
FORCEPROP 1 LAST TOLERANCE 5%
J 0
(6425 5550);
DISPLAY 0.510638 (6425 5550);
FORCEPROP 1 LAST $LOCATION R2922
J 0
(6025 5550);
DISPLAY 0.638298 (6025 5550);
FORCEPROP 1 LASTPIN (6150 5550) $PN 1
J 0
(6162 5562);
DISPLAY 0.787234 (6162 5562);
PAINT MONO (6162 5562);
FORCEPROP 1 LASTPIN (6350 5550) $PN 2
J 0
(6312 5562);
DISPLAY 0.787234 (6312 5562);
PAINT MONO (6312 5562);
FORCEPROP 1 LAST PATH I95
J 0
(6200 5700);
DISPLAY 0.978723 (6200 5700);
PAINT WHITE (6200 5700);
DISPLAY INVISIBLE (6200 5700);
FORCEPROP 2 LAST CDS_LIB pure_quanta
J 0
(6250 5550);
DISPLAY INVISIBLE (6250 5550);
FORCEPROP 1 LAST WATTAGE 1/16W
J 2
(6350 5475);
DISPLAY 0.319149 (6350 5475);
DISPLAY INVISIBLE (6350 5475);
FORCEPROP 1 LAST PACK_TYPE 0402LF
J 0
(6500 5550);
DISPLAY 0.510638 (6500 5550);
DISPLAY INVISIBLE (6500 5550);
FORCEPROP 0 LAST CDS_LOCATION R2922
J 0
(6025 5600);
DISPLAY 1.021277 (6025 5600);
DISPLAY INVISIBLE (6025 5600);
FORCEPROP 0 LAST $SEC 1
J 0
(6025 5600);
DISPLAY 0.680851 (6025 5600);
PAINT MONO (6025 5600);
DISPLAY INVISIBLE (6025 5600);
FORCEPROP 0 LAST CDS_SEC 1
J 0
(6025 5600);
DISPLAY 1.021277 (6025 5600);
DISPLAY INVISIBLE (6025 5600);
FORCEADD Q_RES..1
(8675 3525);
FORCEPROP 1 LAST PART_NUMBER CS00002JB13
J 0
(8625 3575);
DISPLAY 0.404255 (8625 3575);
DISPLAY INVISIBLE (8625 3575);
FORCEPROP 1 LAST MATERIAL CHIP
J 0
(8925 3525);
DISPLAY 0.510638 (8925 3525);
FORCEPROP 1 LAST TOLERANCE 5%
J 0
(8850 3525);
DISPLAY 0.510638 (8850 3525);
FORCEPROP 1 LAST VALUE 0
J 2
(8825 3525);
DISPLAY 0.510638 (8825 3525);
FORCEPROP 1 LAST $LOCATION R2982
J 0
(8475 3525);
DISPLAY 0.510638 (8475 3525);
FORCEPROP 1 LASTPIN (8575 3525) $PN 1
J 0
(8587 3537);
DISPLAY 0.787234 (8587 3537);
PAINT MONO (8587 3537);
FORCEPROP 1 LASTPIN (8775 3525) $PN 2
J 0
(8737 3537);
DISPLAY 0.787234 (8737 3537);
PAINT MONO (8737 3537);
FORCEPROP 1 LAST PATH I96
J 0
(8625 3675);
DISPLAY 0.978723 (8625 3675);
PAINT WHITE (8625 3675);
DISPLAY INVISIBLE (8625 3675);
FORCEPROP 2 LAST CDS_LIB pure_quanta
J 0
(8675 3525);
DISPLAY INVISIBLE (8675 3525);
FORCEPROP 1 LAST PACK_TYPE 0402LF
J 0
(8925 3525);
DISPLAY 0.510638 (8925 3525);
DISPLAY INVISIBLE (8925 3525);
FORCEPROP 1 LAST WATTAGE 1/16W
J 2
(8850 3600);
DISPLAY 0.404255 (8850 3600);
DISPLAY INVISIBLE (8850 3600);
FORCEPROP 0 LAST CDS_LOCATION R2982
J 0
(8925 3550);
DISPLAY 1.021277 (8925 3550);
DISPLAY INVISIBLE (8925 3550);
FORCEPROP 0 LAST $SEC 1
J 0
(8925 3550);
DISPLAY 0.680851 (8925 3550);
PAINT MONO (8925 3550);
DISPLAY INVISIBLE (8925 3550);
FORCEPROP 0 LAST CDS_SEC 1
J 0
(8925 3550);
DISPLAY 1.021277 (8925 3550);
DISPLAY INVISIBLE (8925 3550);
FORCEADD OFFPAGE..2
(9950 3525);
FORCEPROP 2 LAST $XR0 227 
J 0
(10139 3525);
DISPLAY 0.638298 (10139 3525);
PAINT MONO (10139 3525);
FORCEPROP 2 LAST PATH I97
J 0
(10150 3575);
DISPLAY 1.021277 (10150 3575);
DISPLAY INVISIBLE (10150 3575);
FORCEPROP 2 LAST CDS_LIB standard
J 0
(9950 3525);
PAINT MONO (9950 3525);
DISPLAY INVISIBLE (9950 3525);
FORCEPROP 1 LAST OFFPAGE TRUE
J 0
(10275 3400);
DISPLAY 0.872340 (10275 3400);
PAINT GREEN (10275 3400);
DISPLAY INVISIBLE (10275 3400);
FORCEPROP 1 LAST COMMENT_BODY TRUE
J 0
(9905 3430);
DISPLAY 0.872340 (9905 3430);
PAINT PEACH (9905 3430);
DISPLAY INVISIBLE (9905 3430);
FORCEADD OFFPAGE..1
(7450 3525);
FORCEPROP 2 LAST $XR0 231 
J 0
(7198 3525);
DISPLAY 0.638298 (7198 3525);
PAINT MONO (7198 3525);
FORCEPROP 2 LAST PATH I98
J 0
(7175 3575);
DISPLAY 1.021277 (7175 3575);
DISPLAY INVISIBLE (7175 3575);
FORCEPROP 2 LAST CDS_LIB standard
J 0
(7450 3525);
DISPLAY INVISIBLE (7450 3525);
FORCEPROP 1 LAST COMMENT_BODY TRUE
J 0
(7575 3425);
DISPLAY 1.170213 (7575 3425);
PAINT GREEN (7575 3425);
DISPLAY INVISIBLE (7575 3425);
FORCEPROP 1 LAST OFFPAGE TRUE
J 0
(7775 3400);
DISPLAY 0.872340 (7775 3400);
DISPLAY INVISIBLE (7775 3400);
FORCEADD OFFPAGE..1
(7450 3325);
FORCEPROP 2 LAST $XR0 231 
J 0
(7198 3325);
DISPLAY 0.638298 (7198 3325);
PAINT MONO (7198 3325);
FORCEPROP 2 LAST PATH I99
J 0
(7175 3375);
DISPLAY 1.021277 (7175 3375);
DISPLAY INVISIBLE (7175 3375);
FORCEPROP 1 LAST OFFPAGE TRUE
J 0
(7775 3200);
DISPLAY 0.872340 (7775 3200);
DISPLAY INVISIBLE (7775 3200);
FORCEPROP 1 LAST COMMENT_BODY TRUE
J 0
(7575 3225);
DISPLAY 1.170213 (7575 3225);
PAINT GREEN (7575 3225);
DISPLAY INVISIBLE (7575 3225);
FORCEPROP 2 LAST CDS_LIB standard
J 0
(7450 3325);
DISPLAY INVISIBLE (7450 3325);
FORCEADD DNS..2
(5100 3350);
PAINT RED (5100 3350);
FORCEPROP 2 LAST CDS_LIB mstr_misc
J 0
(5100 3350);
PAINT MONO (5100 3350);
DISPLAY INVISIBLE (5100 3350);
FORCEPROP 1 LAST COMMENT_BODY TRUE
J 0
(5100 3350);
DISPLAY INVISIBLE (5100 3350);
FORCEADD DNS..2
(5900 5900);
PAINT RED (5900 5900);
FORCEPROP 1 LAST COMMENT_BODY TRUE
J 0
(5900 5900);
DISPLAY INVISIBLE (5900 5900);
FORCEPROP 2 LAST CDS_LIB mstr_misc
J 0
(5900 5900);
DISPLAY INVISIBLE (5900 5900);
FORCEADD DNS..2
(5355 3370);
PAINT RED (5355 3370);
FORCEPROP 1 LAST COMMENT_BODY TRUE
J 0
(5355 3370);
DISPLAY INVISIBLE (5355 3370);
FORCEPROP 2 LAST CDS_LIB mstr_misc
J 0
(5355 3370);
PAINT MONO (5355 3370);
DISPLAY INVISIBLE (5355 3370);
FORCEADD QUANTA_TITLE_BLOCK_C..1
(12925 525);
FORCEPROP 0 LAST CDS_CON_LAST_MODIFIED Fri Aug 25 14:03:49 2023
J 0
(11040 540);
DISPLAY INVISIBLE (11040 540);
FORCEPROP 1 LAST CUSTOM_TXT_CDS <CON_LAST_MODIFIED>
J 0
(11040 540);
DISPLAY 0.978723 (11040 540);
FORCEPROP 2 LAST CUSTOM_TXT_CDS <XR_PAGE_TITLE>
J 0
(5035 5775);
DISPLAY 0.638298 (5035 5775);
PAINT PINK (5035 5775);
DISPLAY INVISIBLE (5035 5775);
FORCEPROP 1 LAST CUSTOM_TXT_CDS <NAME_2>
J 0
(9750 575);
FORCEPROP 1 LAST CUSTOM_TXT_CDS <NAME_1>
J 0
(9750 700);
FORCEPROP 1 LAST CUSTOM_TXT_CDS <Q_NUMBER>
J 0
(11522 628);
DISPLAY 1.212766 (11522 628);
FORCEPROP 1 LAST CUSTOM_TXT_CDS <Q_PROJ>
J 0
(10543 627);
DISPLAY 1.212766 (10543 627);
FORCEPROP 1 LAST CUSTOM_TXT_CDS <Q_REV>
J 0
(12741 628);
DISPLAY 1.212766 (12741 628);
FORCEPROP 1 LAST CUSTOM_TXT_CDS <CON_PAGE_NUM> OF <CON_TOTAL_PAGES>
J 0
(12479 543);
DISPLAY 0.978723 (12479 543);
FORCEPROP 1 LAST Q_TITLE BMC - PCA9539
J 0
(3559 551);
DISPLAY 2.446809 (3559 551);
PAINT GREEN (3559 551);
FORCEPROP 1 LAST Q_DEPT 
J 1
(9162 574);
DISPLAY 1.957447 (9162 574);
PAINT GREEN (9162 574);
FORCEPROP 2 LAST CDS_XR_PAGE_TITLE CR-227 : @S9S_MB_2U_LIB.S9S_MB_2U(SCH_1):PAGE227
J 0
(5035 5775);
DISPLAY 0.638298 (5035 5775);
PAINT PINK (5035 5775);
DISPLAY INVISIBLE (5035 5775);
FORCEPROP 2 LAST PAGE_BORDER TRUE
J 0
(5035 5775);
DISPLAY 0.638298 (5035 5775);
PAINT PINK (5035 5775);
DISPLAY INVISIBLE (5035 5775);
FORCEPROP 1 LAST COMMENT_BODY TRUE
J 0
(12937 512);
DISPLAY 0.978723 (12937 512);
PAINT GREEN (12937 512);
DISPLAY INVISIBLE (12937 512);
FORCEPROP 1 LAST CDS_LMAN_SYM_OUTLINE -9475,6775,100,-125
J 0
(12925 525);
DISPLAY 0.468085 (12925 525);
PAINT GREEN (12925 525);
DISPLAY INVISIBLE (12925 525);
FORCEPROP 2 LAST CDS_LIB pure_quanta
J 0
(12925 525);
DISPLAY INVISIBLE (12925 525);
WIRE 16 -1 (9000 4325)(9000 4375);
WIRE 16 -1 (8425 4325)(9000 4325);
WIRE 16 -1 (9000 4250)(9000 4325);
WIRE 16 -1 (6675 6225)(6675 6150);
WIRE 16 -1 (5900 6150)(5900 6025);
WIRE 16 -1 (5100 3725)(5100 3650);
WIRE 16 -1 (7325 4650)(7325 4475);
WIRE 16 -1 (7325 4650)(7475 4650);
WIRE 16 -1 (9000 4050)(9000 3975);
WIRE 16 -1 (5350 2675)(5350 2600);
WIRE 16 -1 (5100 2675)(5100 2600);
WIRE 16 2175 (7000 925)(10375 925);
WIRE 16 2175 (10375 1075)(10375 925);
WIRE 16 2175 (7000 1075)(7000 925);
WIRE 16 2175 (7000 1075)(10375 1075);
WIRE 16 -1 (7475 975)(8550 975);
FORCEPROP 2 LAST SIG_NAME PRSNT_CABLE_GPU_A3_ISO_N
J 0
(7540 985);
DISPLAY 0.638298 (7540 985);
WIRE 16 -1 (8750 975)(9900 975);
FORCEPROP 2 LAST SIG_NAME PRSNT_CABLE_GPU_A3_ISO_R_N
J 0
(9065 985);
DISPLAY 0.638298 (9065 985);
WIRE 16 -1 (8275 5050)(9150 5050);
FORCEPROP 2 LAST SIG_NAME PRSNT_CABLE_GPU_A3_ISO_R_N
J 0
(8390 5060);
DISPLAY 0.638298 (8390 5060);
PAINT WHITE (8390 5060);
WIRE 16 2175 (7000 1175)(10375 1175);
WIRE 16 2175 (10375 2325)(10375 1175);
WIRE 16 2175 (7000 2325)(7000 1175);
WIRE 16 2175 (7000 2325)(10375 2325);
WIRE 16 -1 (5100 3475)(5100 3650);
WIRE 16 -1 (5350 3650)(5100 3650);
WIRE 16 -1 (5350 3475)(5350 3650);
WIRE 16 -1 (8425 4650)(8425 4325);
FORCEPROP 0 LAST VOLTAGE 3.3
J 0
(8425 4487);
DISPLAY INVISIBLE (8425 4487);
WIRE 16 -1 (8275 4650)(8425 4650);
WIRE 16 -1 (8750 1300)(9875 1300);
FORCEPROP 0 LAST CDS_PHYS_NET_NAME CLK_25M_OSC_FPGA_R
J 0
(8775 1342);
PAINT MONO (8775 1342);
DISPLAY INVISIBLE (8775 1342);
FORCEPROP 0 LAST SIG_NAME PRSNT_CABLE_GPU_A1_ISO_R1_N
J 0
(9065 1310);
DISPLAY 0.553191 (9065 1310);
PAINT WHITE (9065 1310);
WIRE 16 -1 (8750 1750)(9875 1750);
FORCEPROP 2 LAST SIG_NAME PRSNT_CABLE_SWB_B2_ISO_R_N
J 0
(9065 1760);
DISPLAY 0.638298 (9065 1760);
WIRE 16 -1 (8750 2050)(9875 2050);
FORCEPROP 0 LAST CDS_PHYS_NET_NAME FM_GPU_POWER_EN_R
J 0
(9065 2090);
PAINT MONO (9065 2090);
DISPLAY INVISIBLE (9065 2090);
FORCEPROP 2 LAST SIG_NAME GPU_PRSNT_N_ISO_R1
J 0
(9065 2060);
DISPLAY 0.638298 (9065 2060);
PAINT WHITE (9065 2060);
WIRE 16 -1 (8750 2200)(9875 2200);
FORCEPROP 0 LAST CDS_PHYS_NET_NAME FM_GPU_POWER_EN_R
J 0
(9065 2240);
PAINT MONO (9065 2240);
DISPLAY INVISIBLE (9065 2240);
FORCEPROP 2 LAST SIG_NAME PRSNT_SWB_ISO_R1_N
J 0
(9065 2210);
DISPLAY 0.638298 (9065 2210);
PAINT WHITE (9065 2210);
WIRE 16 2175 (8425 2475)(9050 2475);
WIRE 16 2175 (9050 3200)(9050 2475);
WIRE 16 2175 (8425 3200)(8425 2475);
WIRE 16 2175 (8425 3200)(9050 3200);
WIRE 16 -1 (8775 3325)(9900 3325);
FORCEPROP 0 LAST CDS_PHYS_NET_NAME RST_MB_BMC_RST_BIC_R
J 0
(9090 3365);
PAINT MONO (9090 3365);
DISPLAY INVISIBLE (9090 3365);
FORCEPROP 2 LAST SIG_NAME SMB_IOEXP_3V3AUX_SDA_R1
J 0
(9090 3335);
DISPLAY 0.638298 (9090 3335);
PAINT WHITE (9090 3335);
WIRE 16 -1 (8775 3525)(9900 3525);
FORCEPROP 0 LAST CDS_PHYS_NET_NAME FM_GPU_POWER_EN_R
J 0
(9090 3565);
PAINT MONO (9090 3565);
DISPLAY INVISIBLE (9090 3565);
FORCEPROP 2 LAST SIG_NAME SMB_IOEXP_3V3AUX_SCL_R1
J 0
(9090 3535);
DISPLAY 0.638298 (9090 3535);
PAINT WHITE (9090 3535);
WIRE 16 -1 (8775 3750)(9900 3750);
FORCEPROP 0 LAST CDS_PHYS_NET_NAME FM_GPU_POWER_EN_R
J 0
(9090 3790);
PAINT MONO (9090 3790);
DISPLAY INVISIBLE (9090 3790);
FORCEPROP 2 LAST SIG_NAME RST_SWB_BIC_R_N
J 0
(9090 3760);
DISPLAY 0.638298 (9090 3760);
PAINT WHITE (9090 3760);
WIRE 16 -1 (8275 4750)(9125 4750);
FORCEPROP 0 LAST CDS_PHYS_NET_NAME SMB_PEHPCPU1_LVC3_R2_SCL
J 0
(8715 4792);
PAINT MONO (8715 4792);
DISPLAY INVISIBLE (8715 4792);
FORCEPROP 2 LAST SIG_NAME SMB_IOEXP_3V3AUX_SDA_R1
J 0
(8390 4760);
DISPLAY 0.553191 (8390 4760);
PAINT WHITE (8390 4760);
WIRE 16 -1 (8275 4850)(9125 4850);
FORCEPROP 0 LAST CDS_PHYS_NET_NAME SMB_PEHPCPU1_LVC3_R2_SDA
J 0
(8715 4892);
PAINT MONO (8715 4892);
DISPLAY INVISIBLE (8715 4892);
FORCEPROP 2 LAST SIG_NAME SMB_IOEXP_3V3AUX_SCL_R1
J 0
(8390 4860);
DISPLAY 0.553191 (8390 4860);
PAINT WHITE (8390 4860);
WIRE 16 -1 (8275 4950)(9125 4950);
FORCEPROP 0 LAST CDS_PHYS_NET_NAME TP_PCA9555_2_P17
J 0
(8940 4992);
PAINT MONO (8940 4992);
DISPLAY INVISIBLE (8940 4992);
FORCEPROP 2 LAST SIG_NAME TCA9539_0_ADD0
J 0
(8390 4960);
DISPLAY 0.553191 (8390 4960);
PAINT WHITE (8390 4960);
FORCEPROP 0 LAST $PHYS_NET_NAME RST_PCIE_M2_N
J 0
(8940 5039);
PAINT MONO (8940 5039);
DISPLAY INVISIBLE (8940 5039);
WIRE 16 -1 (8275 5250)(9150 5250);
FORCEPROP 0 LAST CDS_PHYS_NET_NAME TP_PCA9555_2_P15
J 0
(8965 5292);
PAINT MONO (8965 5292);
DISPLAY INVISIBLE (8965 5292);
FORCEPROP 2 LAST SIG_NAME GPU_PEX_STRAP1_R
J 0
(8390 5260);
DISPLAY 0.553191 (8390 5260);
PAINT WHITE (8390 5260);
FORCEPROP 0 LAST $PHYS_NET_NAME RST_PCIE_M2_N
J 0
(8965 5339);
PAINT MONO (8965 5339);
DISPLAY INVISIBLE (8965 5339);
WIRE 16 -1 (7475 2200)(8550 2200);
FORCEPROP 0 LAST CDS_PHYS_NET_NAME FM_GPU_POWER_EN
J 0
(7500 2242);
PAINT MONO (7500 2242);
DISPLAY INVISIBLE (7500 2242);
FORCEPROP 0 LAST SIG_NAME PRSNT_SWB_ISO_N
J 0
(7575 2210);
DISPLAY 0.680851 (7575 2210);
PAINT WHITE (7575 2210);
WIRE 16 -1 (7475 2050)(8550 2050);
FORCEPROP 0 LAST CDS_PHYS_NET_NAME FM_GPU_POWER_EN
J 0
(7500 2092);
PAINT MONO (7500 2092);
DISPLAY INVISIBLE (7500 2092);
FORCEPROP 0 LAST SIG_NAME GPU_PRSNT_N_ISO
J 0
(7575 2060);
DISPLAY 0.680851 (7575 2060);
PAINT WHITE (7575 2060);
WIRE 16 -1 (7475 1450)(8550 1450);
FORCEPROP 2 LAST SIG_NAME PRSNT_CABLE_SWB_B1_ISO_N
J 0
(7540 1460);
DISPLAY 0.638298 (7540 1460);
WIRE 16 -1 (7475 1300)(8550 1300);
FORCEPROP 0 LAST CDS_PHYS_NET_NAME CLK_25M_OSC_FPGA_R
J 0
(7500 1342);
PAINT MONO (7500 1342);
DISPLAY INVISIBLE (7500 1342);
FORCEPROP 0 LAST SIG_NAME PRSNT_CABLE_GPU_A1_ISO_N
J 0
(7565 1310);
DISPLAY 0.680851 (7565 1310);
PAINT WHITE (7565 1310);
WIRE 16 -1 (8750 1900)(9875 1900);
FORCEPROP 0 LAST CDS_PHYS_NET_NAME FM_GPU_POWER_EN_R
J 0
(9065 1940);
PAINT MONO (9065 1940);
DISPLAY INVISIBLE (9065 1940);
FORCEPROP 2 LAST SIG_NAME PRSNT_CABLE_GPU_B3_ISO_R1_N
J 0
(9065 1910);
DISPLAY 0.638298 (9065 1910);
PAINT WHITE (9065 1910);
WIRE 16 -1 (7475 1900)(8550 1900);
FORCEPROP 0 LAST CDS_PHYS_NET_NAME FM_GPU_POWER_EN
J 0
(7500 1942);
PAINT MONO (7500 1942);
DISPLAY INVISIBLE (7500 1942);
FORCEPROP 0 LAST SIG_NAME PRSNT_CABLE_GPU_B3_ISO_N
J 0
(7575 1910);
DISPLAY 0.680851 (7575 1910);
PAINT WHITE (7575 1910);
WIRE 16 -1 (7475 1750)(8550 1750);
FORCEPROP 2 LAST SIG_NAME PRSNT_CABLE_SWB_B2_ISO_N
J 0
(7540 1760);
DISPLAY 0.638298 (7540 1760);
WIRE 16 -1 (7475 1600)(8550 1600);
FORCEPROP 2 LAST SIG_NAME PRSNT_CABLE_GPU_A2_ISO_N
J 0
(7540 1610);
DISPLAY 0.638298 (7540 1610);
WIRE 16 -1 (8775 2525)(9900 2525);
FORCEPROP 0 LAST CDS_PHYS_NET_NAME FM_GPU_SMB2_ALERT_BUF_R_N
J 0
(9090 2565);
PAINT MONO (9090 2565);
DISPLAY INVISIBLE (9090 2565);
FORCEPROP 2 LAST SIG_NAME GPU_PEX_STRAP0_R
J 0
(9115 2535);
DISPLAY 0.638298 (9115 2535);
PAINT WHITE (9115 2535);
WIRE 16 -1 (8775 2925)(9900 2925);
FORCEPROP 0 LAST CDS_PHYS_NET_NAME RST_MB_BMC_RST_BIC_R
J 0
(9090 2965);
PAINT MONO (9090 2965);
DISPLAY INVISIBLE (9090 2965);
FORCEPROP 2 LAST SIG_NAME GPU_BASE_ID0_R
J 0
(9090 2935);
DISPLAY 0.638298 (9090 2935);
PAINT WHITE (9090 2935);
WIRE 16 -1 (7500 2525)(8575 2525);
FORCEPROP 0 LAST CDS_PHYS_NET_NAME FM_GPU_SMB2_ALERT_BUF_N
J 0
(7525 2567);
PAINT MONO (7525 2567);
DISPLAY INVISIBLE (7525 2567);
FORCEPROP 0 LAST SIG_NAME GPU_PEX_STRAP0
J 0
(7600 2535);
DISPLAY 0.680851 (7600 2535);
PAINT WHITE (7600 2535);
WIRE 16 -1 (7500 2725)(8575 2725);
FORCEPROP 0 LAST CDS_PHYS_NET_NAME FM_GPU_SMB1_ALERT_BUF_N
J 0
(7525 2767);
PAINT MONO (7525 2767);
DISPLAY INVISIBLE (7525 2767);
FORCEPROP 0 LAST SIG_NAME GPU_PEX_STRAP1
J 0
(7600 2735);
DISPLAY 0.680851 (7600 2735);
PAINT WHITE (7600 2735);
WIRE 16 -1 (7500 2925)(8575 2925);
FORCEPROP 0 LAST CDS_PHYS_NET_NAME RST_MB_BMC_RST_BIC
J 0
(7525 2967);
PAINT MONO (7525 2967);
DISPLAY INVISIBLE (7525 2967);
FORCEPROP 0 LAST SIG_NAME GPU_BASE_ID0
J 0
(7600 2935);
DISPLAY 0.680851 (7600 2935);
PAINT WHITE (7600 2935);
WIRE 16 -1 (8275 5150)(9150 5150);
FORCEPROP 0 LAST CDS_PHYS_NET_NAME TP_PCA9555_2_P16
J 0
(8965 5192);
PAINT MONO (8965 5192);
DISPLAY INVISIBLE (8965 5192);
FORCEPROP 2 LAST SIG_NAME PRSNT_CABLE_GPU_A1_ISO_R1_N
J 0
(8390 5160);
DISPLAY 0.553191 (8390 5160);
PAINT WHITE (8390 5160);
FORCEPROP 0 LAST $PHYS_NET_NAME RST_PCIE_M2_N
J 0
(8965 5239);
PAINT MONO (8965 5239);
DISPLAY INVISIBLE (8965 5239);
WIRE 16 -1 (6350 4750)(7475 4750);
FORCEPROP 0 LAST CDS_PHYS_NET_NAME TP_PCA9555_2_P17
J 0
(7290 4792);
PAINT MONO (7290 4792);
DISPLAY INVISIBLE (7290 4792);
FORCEPROP 2 LAST SIG_NAME PRSNT_CABLE_SWB_B2_ISO_R_N
J 0
(6465 4760);
DISPLAY 0.553191 (6465 4760);
PAINT WHITE (6465 4760);
FORCEPROP 0 LAST $PHYS_NET_NAME RST_PCIE_M2_N
J 0
(7290 4839);
PAINT MONO (7290 4839);
DISPLAY INVISIBLE (7290 4839);
WIRE 16 -1 (6350 4850)(7475 4850);
FORCEPROP 0 LAST CDS_PHYS_NET_NAME TP_PCA9555_2_P16
J 0
(7290 4892);
PAINT MONO (7290 4892);
DISPLAY INVISIBLE (7290 4892);
FORCEPROP 2 LAST SIG_NAME PRSNT_CABLE_GPU_B3_ISO_R1_N
J 0
(6465 4860);
DISPLAY 0.553191 (6465 4860);
PAINT WHITE (6465 4860);
FORCEPROP 0 LAST $PHYS_NET_NAME RST_PCIE_M2_N
J 0
(7290 4939);
PAINT MONO (7290 4939);
DISPLAY INVISIBLE (7290 4939);
WIRE 16 -1 (6350 4950)(7475 4950);
FORCEPROP 0 LAST CDS_PHYS_NET_NAME TP_TCA9539_0_P0_7
J 0
(7290 4992);
PAINT MONO (7290 4992);
DISPLAY INVISIBLE (7290 4992);
FORCEPROP 2 LAST SIG_NAME GPU_PRSNT_N_ISO_R1
J 0
(6465 4960);
DISPLAY 0.553191 (6465 4960);
PAINT WHITE (6465 4960);
FORCEPROP 0 LAST $PHYS_NET_NAME RST_PCIE_M2_N
J 0
(7290 5039);
PAINT MONO (7290 5039);
DISPLAY INVISIBLE (7290 5039);
WIRE 16 -1 (6350 5050)(7475 5050);
FORCEPROP 0 LAST CDS_PHYS_NET_NAME TP_TCA9539_0_P0_6
J 0
(7290 5092);
PAINT MONO (7290 5092);
DISPLAY INVISIBLE (7290 5092);
FORCEPROP 2 LAST SIG_NAME PRSNT_SWB_ISO_R1_N
J 0
(6465 5060);
DISPLAY 0.553191 (6465 5060);
PAINT WHITE (6465 5060);
FORCEPROP 0 LAST $PHYS_NET_NAME RST_PCIE_M2_N
J 0
(7290 5139);
PAINT MONO (7290 5139);
DISPLAY INVISIBLE (7290 5139);
WIRE 16 -1 (6350 5150)(7475 5150);
FORCEPROP 0 LAST CDS_PHYS_NET_NAME TP_PCA9555_2_P17
J 0
(7290 5192);
PAINT MONO (7290 5192);
DISPLAY INVISIBLE (7290 5192);
FORCEPROP 2 LAST SIG_NAME TP_TCA9539_0_P0_3
J 0
(6465 5160);
DISPLAY 0.553191 (6465 5160);
PAINT WHITE (6465 5160);
FORCEPROP 0 LAST $PHYS_NET_NAME RST_PCIE_M2_N
J 0
(7290 5239);
PAINT MONO (7290 5239);
DISPLAY INVISIBLE (7290 5239);
WIRE 16 -1 (6350 5250)(7475 5250);
FORCEPROP 0 LAST CDS_PHYS_NET_NAME TP_PCA9555_2_P16
J 0
(7290 5292);
PAINT MONO (7290 5292);
DISPLAY INVISIBLE (7290 5292);
FORCEPROP 2 LAST SIG_NAME TP_TCA9539_0_P0_2
J 0
(6465 5260);
DISPLAY 0.553191 (6465 5260);
PAINT WHITE (6465 5260);
FORCEPROP 0 LAST $PHYS_NET_NAME RST_PCIE_M2_N
J 0
(7290 5339);
PAINT MONO (7290 5339);
DISPLAY INVISIBLE (7290 5339);
WIRE 16 -1 (8775 2725)(9900 2725);
FORCEPROP 0 LAST CDS_PHYS_NET_NAME FM_GPU_SMB1_ALERT_BUF_R_N
J 0
(9090 2765);
PAINT MONO (9090 2765);
DISPLAY INVISIBLE (9090 2765);
FORCEPROP 2 LAST SIG_NAME GPU_PEX_STRAP1_R
J 0
(9115 2735);
DISPLAY 0.638298 (9115 2735);
PAINT WHITE (9115 2735);
WIRE 16 -1 (8750 1450)(9875 1450);
FORCEPROP 2 LAST SIG_NAME PRSNT_CABLE_SWB_B1_ISO_R_N
J 0
(9065 1460);
DISPLAY 0.638298 (9065 1460);
WIRE 16 -1 (7500 3125)(8575 3125);
FORCEPROP 0 LAST CDS_PHYS_NET_NAME FM_GPU_POWER_EN
J 0
(7525 3167);
PAINT MONO (7525 3167);
DISPLAY INVISIBLE (7525 3167);
FORCEPROP 0 LAST SIG_NAME GPU_BASE_ID1
J 0
(7600 3135);
DISPLAY 0.680851 (7600 3135);
PAINT WHITE (7600 3135);
WIRE 16 -1 (7500 3325)(8575 3325);
FORCEPROP 0 LAST CDS_PHYS_NET_NAME RST_MB_BMC_RST_BIC
J 0
(7525 3367);
PAINT MONO (7525 3367);
DISPLAY INVISIBLE (7525 3367);
FORCEPROP 0 LAST SIG_NAME SMB_IOEXP_3V3AUX_SDA
J 0
(7600 3335);
DISPLAY 0.680851 (7600 3335);
PAINT WHITE (7600 3335);
WIRE 16 -1 (7500 3525)(8575 3525);
FORCEPROP 0 LAST CDS_PHYS_NET_NAME FM_GPU_POWER_EN
J 0
(7525 3567);
PAINT MONO (7525 3567);
DISPLAY INVISIBLE (7525 3567);
FORCEPROP 0 LAST SIG_NAME SMB_IOEXP_3V3AUX_SCL
J 0
(7600 3535);
DISPLAY 0.680851 (7600 3535);
PAINT WHITE (7600 3535);
WIRE 16 -1 (7500 3750)(8575 3750);
FORCEPROP 0 LAST CDS_PHYS_NET_NAME FM_GPU_POWER_EN
J 0
(7525 3792);
PAINT MONO (7525 3792);
DISPLAY INVISIBLE (7525 3792);
FORCEPROP 0 LAST SIG_NAME RST_SWB_BIC_N
J 0
(7600 3760);
DISPLAY 0.680851 (7600 3760);
PAINT WHITE (7600 3760);
WIRE 16 -1 (8750 1600)(9875 1600);
FORCEPROP 2 LAST SIG_NAME PRSNT_CABLE_GPU_A2_ISO_R1_N
J 0
(9065 1610);
DISPLAY 0.638298 (9065 1610);
WIRE 16 -1 (8775 3125)(9900 3125);
FORCEPROP 0 LAST CDS_PHYS_NET_NAME FM_GPU_POWER_EN_R
J 0
(9090 3165);
PAINT MONO (9090 3165);
DISPLAY INVISIBLE (9090 3165);
FORCEPROP 2 LAST SIG_NAME GPU_BASE_ID1_R
J 0
(9090 3135);
DISPLAY 0.638298 (9090 3135);
PAINT WHITE (9090 3135);
WIRE 16 -1 (6350 5650)(7475 5650);
FORCEPROP 0 LAST CDS_PHYS_NET_NAME TP_PCA9555_2_P00
J 0
(7290 5692);
PAINT MONO (7290 5692);
DISPLAY INVISIBLE (7290 5692);
FORCEPROP 2 LAST SIG_NAME TCA9539_0_ADD1
J 0
(6465 5660);
DISPLAY 0.553191 (6465 5660);
PAINT WHITE (6465 5660);
FORCEPROP 0 LAST $PHYS_NET_NAME RST_PCIE_M2_N
J 0
(7290 5739);
PAINT MONO (7290 5739);
DISPLAY INVISIBLE (7290 5739);
WIRE 16 -1 (8275 5750)(9150 5750);
FORCEPROP 0 LAST CDS_PHYS_NET_NAME TP_PCA9555_2_P16
J 0
(8965 5792);
PAINT MONO (8965 5792);
DISPLAY INVISIBLE (8965 5792);
FORCEPROP 2 LAST SIG_NAME PRSNT_CABLE_GPU_A2_ISO_R1_N
J 0
(8390 5760);
DISPLAY 0.553191 (8390 5760);
PAINT WHITE (8390 5760);
FORCEPROP 0 LAST $PHYS_NET_NAME RST_PCIE_M2_N
J 0
(8965 5839);
PAINT MONO (8965 5839);
DISPLAY INVISIBLE (8965 5839);
WIRE 16 -1 (8275 5650)(9150 5650);
FORCEPROP 0 LAST CDS_PHYS_NET_NAME TP_PCA9555_2_P17
J 0
(8965 5692);
PAINT MONO (8965 5692);
DISPLAY INVISIBLE (8965 5692);
FORCEPROP 2 LAST SIG_NAME PRSNT_CABLE_SWB_B1_ISO_R_N
J 0
(8390 5660);
DISPLAY 0.553191 (8390 5660);
PAINT WHITE (8390 5660);
FORCEPROP 0 LAST $PHYS_NET_NAME RST_PCIE_M2_N
J 0
(8965 5739);
PAINT MONO (8965 5739);
DISPLAY INVISIBLE (8965 5739);
WIRE 16 -1 (8275 5550)(9150 5550);
FORCEPROP 0 LAST CDS_PHYS_NET_NAME E1S_7_BUF_EN
J 0
(8565 5592);
PAINT MONO (8565 5592);
DISPLAY INVISIBLE (8565 5592);
FORCEPROP 2 LAST SIG_NAME GPU_BASE_ID0_R
J 0
(8390 5560);
DISPLAY 0.553191 (8390 5560);
PAINT WHITE (8390 5560);
FORCEPROP 0 LAST $PHYS_NET_NAME RST_PCIE_M2_N
J 0
(8565 5639);
PAINT MONO (8565 5639);
DISPLAY INVISIBLE (8565 5639);
WIRE 16 -1 (5350 3125)(5350 2875);
WIRE 16 -1 (5350 3275)(5350 3125);
WIRE 16 -1 (5350 3125)(6175 3125);
FORCEPROP 0 LAST CDS_PHYS_NET_NAME PCA9555_2_ADD0
J 0
(5790 3167);
PAINT MONO (5790 3167);
DISPLAY INVISIBLE (5790 3167);
FORCEPROP 2 LAST SIG_NAME TCA9539_0_ADD0
J 0
(5565 3135);
DISPLAY 0.553191 (5565 3135);
PAINT WHITE (5565 3135);
WIRE 16 -1 (5100 3025)(5100 2875);
WIRE 16 -1 (5100 3275)(5100 3025);
WIRE 16 -1 (6175 3025)(5100 3025);
FORCEPROP 0 LAST CDS_PHYS_NET_NAME PCA9555_2_ADD1
J 0
(5790 3067);
PAINT MONO (5790 3067);
DISPLAY INVISIBLE (5790 3067);
FORCEPROP 2 LAST SIG_NAME TCA9539_0_ADD1
J 0
(5565 3035);
DISPLAY 0.553191 (5565 3035);
PAINT WHITE (5565 3035);
WIRE 16 -1 (6675 5750)(6675 5950);
WIRE 16 -1 (7475 5750)(6675 5750);
FORCEPROP 2 LAST SIG_NAME PU_U181_INT
J 0
(6840 5760);
DISPLAY 0.510638 (6840 5760);
PAINT WHITE (6840 5760);
WIRE 16 -1 (8275 5450)(9150 5450);
FORCEPROP 0 LAST CDS_PHYS_NET_NAME TP_PCA9555_2_P13
J 0
(8965 5492);
PAINT MONO (8965 5492);
DISPLAY INVISIBLE (8965 5492);
FORCEPROP 2 LAST SIG_NAME GPU_BASE_ID1_R
J 0
(8390 5460);
DISPLAY 0.553191 (8390 5460);
PAINT WHITE (8390 5460);
FORCEPROP 0 LAST $PHYS_NET_NAME RST_PCIE_M2_N
J 0
(8965 5539);
PAINT MONO (8965 5539);
DISPLAY INVISIBLE (8965 5539);
WIRE 16 -1 (5900 5825)(5900 5550);
WIRE 16 -1 (5900 5550)(6150 5550);
WIRE 16 -1 (5125 5550)(5900 5550);
FORCEPROP 0 LAST CDS_PHYS_NET_NAME RST_SMB_SWITCH_N
J 0
(5165 5598);
PAINT MONO (5165 5598);
DISPLAY INVISIBLE (5165 5598);
FORCEPROP 2 LAST SIG_NAME RST_SMB_SWITCH_N
J 0
(5240 5560);
DISPLAY 0.510638 (5240 5560);
PAINT WHITE (5240 5560);
WIRE 16 -1 (8275 5350)(9150 5350);
FORCEPROP 0 LAST CDS_PHYS_NET_NAME E1S_7_BUF_PRSNT_N
J 0
(8565 5392);
PAINT MONO (8565 5392);
DISPLAY INVISIBLE (8565 5392);
FORCEPROP 2 LAST SIG_NAME GPU_PEX_STRAP0_R
J 0
(8390 5360);
DISPLAY 0.553191 (8390 5360);
PAINT WHITE (8390 5360);
FORCEPROP 0 LAST $PHYS_NET_NAME RST_PCIE_M2_N
J 0
(8565 5439);
PAINT MONO (8565 5439);
DISPLAY INVISIBLE (8565 5439);
WIRE 16 -1 (6600 5350)(7475 5350);
FORCEPROP 0 LAST CDS_PHYS_NET_NAME RST_SWB_BIC_N
J 0
(7290 5392);
PAINT MONO (7290 5392);
DISPLAY INVISIBLE (7290 5392);
FORCEPROP 2 LAST SIG_NAME RST_SWB_BIC_N
J 0
(6715 5360);
DISPLAY 0.553191 (6715 5360);
PAINT WHITE (6715 5360);
FORCEPROP 0 LAST $PHYS_NET_NAME RST_PCIE_M2_N
J 0
(7290 5439);
PAINT MONO (7290 5439);
DISPLAY INVISIBLE (7290 5439);
WIRE 16 -1 (7475 5550)(6350 5550);
FORCEPROP 0 LAST CDS_PHYS_NET_NAME PU_RST_SMB_PCIE0_N
J 0
(6390 5598);
PAINT MONO (6390 5598);
DISPLAY INVISIBLE (6390 5598);
FORCEPROP 2 LAST SIG_NAME PU_RST_SMB_U181_N
J 0
(6840 5560);
DISPLAY 0.510638 (6840 5560);
PAINT WHITE (6840 5560);
WIRE 16 -1 (6600 5450)(7475 5450);
FORCEPROP 0 LAST CDS_PHYS_NET_NAME RST_USB_HUB_N
J 0
(6940 5492);
PAINT MONO (6940 5492);
DISPLAY INVISIBLE (6940 5492);
FORCEPROP 2 LAST SIG_NAME RST_USB_HUB_N
J 0
(6715 5460);
DISPLAY 0.553191 (6715 5460);
PAINT WHITE (6715 5460);
FORCEPROP 0 LAST $PHYS_NET_NAME RST_PCIE_M2_N
J 0
(6940 5539);
PAINT MONO (6940 5539);
DISPLAY INVISIBLE (6940 5539);
DOT 1 (9000 4325);
DOT 1 (5900 5550);
DOT 1 (5100 3650);
DOT 1 (5350 3125);
DOT 1 (5100 3025);
FORCENOTE
202120812 ADD R4802
(7050 850) 0;
DISPLAY LEFT (7050 850);
DISPLAY 1.276596 (7050 850);
PAINT PINK (7050 850);
FORCENOTE
202120802 ADD R4728,R4729,R4734,R4735,R4736,R4741,R4742
(7050 1100) 0;
DISPLAY LEFT (7050 1100);
DISPLAY 1.276596 (7050 1100);
PAINT PINK (7050 1100);
FORCENOTE
20211130 POP R3499,R3516,R3517,R3518
(7750 2400) 0;
DISPLAY LEFT (7750 2400);
DISPLAY 1.276596 (7750 2400);
PAINT PINK (7750 2400);
FORCENOTE
20220215 DESIGN CHANGE
(8100 5875) 0;
DISPLAY LEFT (8100 5875);
DISPLAY 1.276596 (8100 5875);
PAINT PINK (8100 5875);
FORCENOTE
PCA9555 ADDR: 0XE8
(4675 2250) 0;
DISPLAY LEFT (4675 2250);
DISPLAY 1.595745 (4675 2250);
PAINT SKYBLUE (4675 2250);
QUIT
